FILE_TYPE = MACRO_DRAWING;
SET COLOR_WIRE YELLOW;
SET COLOR_PROP ORANGE;
SET COLOR_DOT WHITE;
SET COLOR_ARC YELLOW;
SET COLOR_BODY GREEN;
SET COLOR_NOTE PURPLE;
SET PROP_DISPLAY VALUE;
SET PAGE_NUMBER P274;
FORCEADD UNIVERSAL_GND..1
(-7950 975);
FORCEPROP 3 LASTPIN (-7950 1025) SIG_NAME GND\g
J 0
(-7940 1035);
DISPLAY 0.659574 (-7940 1035);
PAINT MONO (-7940 1035);
DISPLAY INVISIBLE (-7940 1035);
FORCEPROP 2 LAST CDS_LIB logical_power
J 0
(-7950 975);
PAINT MONO (-7950 975);
DISPLAY INVISIBLE (-7950 975);
FORCEPROP 1 LAST HDL_POWER GND
J 1
(-7925 900);
DISPLAY 0.872340 (-7925 900);
PAINT GREEN (-7925 900);
DISPLAY INVISIBLE (-7925 900);
FORCEPROP 1 LAST PATH I1
J 0
(-7875 975);
DISPLAY 0.872340 (-7875 975);
PAINT AQUA (-7875 975);
DISPLAY INVISIBLE (-7875 975);
FORCEADD UNIVERSAL_GND..1
(-7550 1950);
FORCEPROP 3 LASTPIN (-7550 2000) SIG_NAME GND\g
J 0
(-7540 2010);
DISPLAY 0.659574 (-7540 2010);
PAINT MONO (-7540 2010);
DISPLAY INVISIBLE (-7540 2010);
FORCEPROP 2 LAST CDS_LIB logical_power
J 0
(-7550 1950);
PAINT MONO (-7550 1950);
DISPLAY INVISIBLE (-7550 1950);
FORCEPROP 1 LAST HDL_POWER GND
J 1
(-7525 1875);
DISPLAY 0.872340 (-7525 1875);
PAINT GREEN (-7525 1875);
DISPLAY INVISIBLE (-7525 1875);
FORCEPROP 1 LAST PATH I10
J 0
(-7475 1950);
DISPLAY 0.872340 (-7475 1950);
PAINT AQUA (-7475 1950);
DISPLAY INVISIBLE (-7475 1950);
FORCEADD ISL99390FRZTR5935..1
(-6025 1700);
FORCEPROP 1 LAST PART_NUMBER AL099390004
J 0
(-6325 2500);
DISPLAY 0.617021 (-6325 2500);
PAINT BLUE (-6325 2500);
DISPLAY INVISIBLE (-6325 2500);
FORCEPROP 2 LAST PART_TYPE SMLF
J 0
(-6325 2700);
DISPLAY 0.638298 (-6325 2700);
FORCEPROP 1 LAST MATERIAL IC
J 0
(-6325 2425);
DISPLAY 0.617021 (-6325 2425);
PAINT SKYBLUE (-6325 2425);
FORCEPROP 2 LAST VALUE ISL99390FRZ-TR5935
J 0
(-6325 2650);
DISPLAY 0.617021 (-6325 2650);
PAINT SKYBLUE (-6325 2650);
FORCEPROP 1 LAST LOCATION PU23_P1_8
J 0
(-6325 2575);
DISPLAY 0.617021 (-6325 2575);
PAINT AQUA (-6325 2575);
FORCEPROP 2 LASTPIN (-5625 1250) $PN 2
J 0
(-5615 1260);
DISPLAY 0.617021 (-5615 1260);
PAINT MONO (-5615 1260);
FORCEPROP 2 LASTPIN (-5625 2050) $PN 33
J 0
(-5615 2060);
DISPLAY 0.617021 (-5615 2060);
PAINT MONO (-5615 2060);
FORCEPROP 2 LASTPIN (-6475 1450) $PN 31
J 2
(-6485 1460);
DISPLAY 0.617021 (-6485 1460);
PAINT MONO (-6485 1460);
FORCEPROP 2 LASTPIN (-6475 1850) $PN 35
J 2
(-6485 1860);
DISPLAY 0.617021 (-6485 1860);
PAINT MONO (-6485 1860);
FORCEPROP 2 LASTPIN (-5625 1400) $PN 6
J 0
(-5615 1410);
DISPLAY 0.617021 (-5615 1410);
PAINT MONO (-5615 1410);
FORCEPROP 2 LASTPIN (-5625 1350) $PN 41
J 0
(-5615 1360);
DISPLAY 0.617021 (-5615 1360);
PAINT MONO (-5615 1360);
FORCEPROP 2 LASTPIN (-6475 1700) $PN 38
J 2
(-6485 1710);
DISPLAY 0.617021 (-6485 1710);
PAINT MONO (-6485 1710);
FORCEPROP 2 LASTPIN (-6475 1400) $PN 37
J 2
(-6485 1410);
DISPLAY 0.617021 (-6485 1410);
PAINT MONO (-6485 1410);
FORCEPROP 2 LASTPIN (-5625 1200) $PN 5
J 0
(-5615 1210);
DISPLAY 0.617021 (-5615 1210);
PAINT MONO (-5615 1210);
FORCEPROP 2 LASTPIN (-5625 1150) $PN 7_9-20_24
J 0
(-5615 1160);
DISPLAY 0.617021 (-5615 1160);
PAINT MONO (-5615 1160);
FORCEPROP 2 LASTPIN (-5625 1100) $PN 40
J 0
(-5615 1110);
DISPLAY 0.617021 (-5615 1110);
PAINT MONO (-5615 1110);
FORCEPROP 2 LASTPIN (-5625 1800) $PN 32
J 0
(-5615 1810);
DISPLAY 0.617021 (-5615 1810);
PAINT MONO (-5615 1810);
FORCEPROP 2 LASTPIN (-6475 2350) $PN 4
J 2
(-6485 2360);
DISPLAY 0.617021 (-6485 2360);
PAINT MONO (-6485 2360);
FORCEPROP 2 LASTPIN (-6475 1100) $PN 34
J 2
(-6485 1110);
DISPLAY 0.617021 (-6485 1110);
PAINT MONO (-6485 1110);
FORCEPROP 2 LASTPIN (-6475 1600) $PN 39
J 2
(-6485 1610);
DISPLAY 0.617021 (-6485 1610);
PAINT MONO (-6485 1610);
FORCEPROP 2 LASTPIN (-5625 1700) $PN 10_19
J 0
(-5615 1710);
DISPLAY 0.617021 (-5615 1710);
PAINT MONO (-5615 1710);
FORCEPROP 2 LASTPIN (-6475 1200) $PN 36
J 2
(-6485 1210);
DISPLAY 0.617021 (-6485 1210);
PAINT MONO (-6485 1210);
FORCEPROP 2 LASTPIN (-6475 2050) $PN 3
J 2
(-6485 2060);
DISPLAY 0.617021 (-6485 2060);
PAINT MONO (-6485 2060);
FORCEPROP 2 LASTPIN (-5625 2350) $PN 25_29
J 0
(-5615 2360);
DISPLAY 0.617021 (-5615 2360);
PAINT MONO (-5615 2360);
FORCEPROP 2 LASTPIN (-5625 2300) $PN 30
J 0
(-5615 2310);
DISPLAY 0.617021 (-5615 2310);
PAINT MONO (-5615 2310);
FORCEPROP 2 LASTPIN (-5625 1450) $PN 1
J 0
(-5615 1460);
DISPLAY 0.617021 (-5615 1460);
PAINT MONO (-5615 1460);
FORCEPROP 1 LAST NEEDS_NO_SIZE TRUE
J 0
(-6025 1700);
DISPLAY 0.723404 (-6025 1700);
PAINT GREEN (-6025 1700);
DISPLAY INVISIBLE (-6025 1700);
FORCEPROP 1 LAST CDS_LMAN_SYM_OUTLINE -300,700,250,-650
J 0
(-6025 1700);
DISPLAY 0.468085 (-6025 1700);
PAINT GREEN (-6025 1700);
DISPLAY INVISIBLE (-6025 1700);
FORCEPROP 2 LAST CDS_LIB pure_quanta
J 0
(-6025 1700);
DISPLAY INVISIBLE (-6025 1700);
FORCEPROP 1 LAST PATH I11
J 0
(-6025 1700);
DISPLAY 0.723404 (-6025 1700);
PAINT GREEN (-6025 1700);
DISPLAY INVISIBLE (-6025 1700);
FORCEPROP 2 LAST $SEC 1
J 0
(-6325 2625);
DISPLAY 0.680851 (-6325 2625);
PAINT MONO (-6325 2625);
DISPLAY INVISIBLE (-6325 2625);
FORCEPROP 2 LAST CDS_SEC 1
J 0
(-6325 2625);
DISPLAY 1.021277 (-6325 2625);
DISPLAY INVISIBLE (-6325 2625);
FORCEADD Q_RES..2
(-7550 2700);
FORCEPROP 1 LAST PART_NUMBER CS-2202FB01
J 0
(-7510 2575);
DISPLAY 0.617021 (-7510 2575);
PAINT BLUE (-7510 2575);
DISPLAY INVISIBLE (-7510 2575);
FORCEPROP 1 LAST WATTAGE 1/16W
J 0
(-7510 2675);
DISPLAY 0.617021 (-7510 2675);
PAINT SKYBLUE (-7510 2675);
FORCEPROP 1 LAST MATERIAL CHIP
J 0
(-7510 2625);
DISPLAY 0.617021 (-7510 2625);
PAINT SKYBLUE (-7510 2625);
FORCEPROP 1 LAST TOLERANCE 1%
J 0
(-7505 2725);
DISPLAY 0.617021 (-7505 2725);
PAINT SKYBLUE (-7505 2725);
FORCEPROP 1 LAST VALUE 2.2
J 0
(-7505 2775);
DISPLAY 0.617021 (-7505 2775);
PAINT SKYBLUE (-7505 2775);
FORCEPROP 1 LAST PACK_TYPE 0402LF
J 0
(-7510 2525);
DISPLAY 0.617021 (-7510 2525);
PAINT SKYBLUE (-7510 2525);
FORCEPROP 1 LAST LOCATION PR287
J 0
(-7505 2825);
DISPLAY 0.617021 (-7505 2825);
PAINT AQUA (-7505 2825);
FORCEPROP 1 LASTPIN (-7550 2800) $PN 1
J 0
(-7545 2762);
DISPLAY 0.617021 (-7545 2762);
PAINT MONO (-7545 2762);
FORCEPROP 1 LASTPIN (-7550 2600) $PN 2
J 0
(-7545 2610);
DISPLAY 0.617021 (-7545 2610);
PAINT MONO (-7545 2610);
FORCEPROP 2 LAST CDS_LIB pure_quanta
J 0
(-7550 2700);
DISPLAY INVISIBLE (-7550 2700);
FORCEPROP 1 LAST PATH I12
J 0
(-7500 2875);
DISPLAY 0.978723 (-7500 2875);
PAINT WHITE (-7500 2875);
DISPLAY INVISIBLE (-7500 2875);
FORCEPROP 1 LAST LOCATION PR287
J 0
(-7500 2875);
DISPLAY 1.021277 (-7500 2875);
PAINT AQUA (-7500 2875);
DISPLAY INVISIBLE (-7500 2875);
FORCEPROP 0 LAST $SEC 1
J 0
(-7500 2875);
DISPLAY 0.680851 (-7500 2875);
PAINT MONO (-7500 2875);
DISPLAY INVISIBLE (-7500 2875);
FORCEPROP 0 LAST CDS_SEC 1
J 0
(-7500 2875);
DISPLAY 1.021277 (-7500 2875);
DISPLAY INVISIBLE (-7500 2875);
FORCEADD VCC15..1
(-7550 3025);
FORCEPROP 3 LASTPIN (-7550 2975) SIG_NAME PVCCIN_CPU1_PVCC\g
J 0
(-7540 2985);
DISPLAY 0.659574 (-7540 2985);
PAINT MONO (-7540 2985);
DISPLAY INVISIBLE (-7540 2985);
FORCEPROP 1 LAST HDL_POWER PVCCIN_CPU1_PVCC
J 1
(-7550 3075);
DISPLAY 0.617021 (-7550 3075);
PAINT GREEN (-7550 3075);
FORCEPROP 2 LAST CDS_LIB logical_power
J 0
(-7550 3025);
DISPLAY INVISIBLE (-7550 3025);
FORCEPROP 1 LAST PATH I13
J 0
(-7500 3050);
DISPLAY 0.872340 (-7500 3050);
PAINT AQUA (-7500 3050);
DISPLAY INVISIBLE (-7500 3050);
FORCEADD UNIVERSAL_GND..1
(-7925 3800);
FORCEPROP 3 LASTPIN (-7925 3850) SIG_NAME GND\g
J 0
(-7915 3860);
DISPLAY 0.659574 (-7915 3860);
PAINT MONO (-7915 3860);
DISPLAY INVISIBLE (-7915 3860);
FORCEPROP 2 LAST CDS_LIB logical_power
J 0
(-7925 3800);
PAINT MONO (-7925 3800);
DISPLAY INVISIBLE (-7925 3800);
FORCEPROP 1 LAST HDL_POWER GND
J 1
(-7900 3725);
DISPLAY 0.872340 (-7900 3725);
PAINT GREEN (-7900 3725);
DISPLAY INVISIBLE (-7900 3725);
FORCEPROP 1 LAST PATH I14
J 0
(-7850 3800);
DISPLAY 0.872340 (-7850 3800);
PAINT AQUA (-7850 3800);
DISPLAY INVISIBLE (-7850 3800);
FORCEADD Q_RES..2
R 2
(-7925 4025);
FORCEPROP 1 LAST PART_NUMBER CS28872FB01
J 2
(-7975 3900);
DISPLAY 0.617021 (-7975 3900);
PAINT BLUE (-7975 3900);
DISPLAY INVISIBLE (-7975 3900);
FORCEPROP 1 LAST WATTAGE 1/16W
J 2
(-7975 4000);
DISPLAY 0.617021 (-7975 4000);
PAINT SKYBLUE (-7975 4000);
FORCEPROP 1 LAST TOLERANCE 1%
J 2
(-7980 4050);
DISPLAY 0.617021 (-7980 4050);
PAINT SKYBLUE (-7980 4050);
FORCEPROP 1 LAST VALUE 8.87K
J 2
(-7980 4100);
DISPLAY 0.617021 (-7980 4100);
PAINT SKYBLUE (-7980 4100);
FORCEPROP 1 LAST PACK_TYPE 0402LF
J 2
(-7975 3850);
DISPLAY 0.617021 (-7975 3850);
PAINT SKYBLUE (-7975 3850);
FORCEPROP 1 LAST MATERIAL EMPTY
J 2
(-7975 3950);
DISPLAY 0.617021 (-7975 3950);
PAINT RED (-7975 3950);
FORCEPROP 1 LAST LOCATION PR286
J 2
(-7970 4150);
DISPLAY 0.617021 (-7970 4150);
PAINT AQUA (-7970 4150);
FORCEPROP 1 LASTPIN (-7925 4125) $PN 1
J 2
(-7930 4087);
DISPLAY 0.617021 (-7930 4087);
PAINT MONO (-7930 4087);
FORCEPROP 1 LASTPIN (-7925 3925) $PN 2
J 2
(-7930 3935);
DISPLAY 0.617021 (-7930 3935);
PAINT MONO (-7930 3935);
FORCEPROP 2 LAST CDS_LIB pure_quanta
J 2
(-7925 4025);
DISPLAY INVISIBLE (-7925 4025);
FORCEPROP 1 LAST PATH I15
J 2
(-7975 4200);
DISPLAY 0.978723 (-7975 4200);
PAINT WHITE (-7975 4200);
DISPLAY INVISIBLE (-7975 4200);
FORCEPROP 1 LAST LOCATION PR286
J 2
(-7975 4200);
DISPLAY 1.021277 (-7975 4200);
PAINT AQUA (-7975 4200);
DISPLAY INVISIBLE (-7975 4200);
FORCEPROP 0 LAST $SEC 1
J 2
(-7975 4200);
DISPLAY 0.680851 (-7975 4200);
PAINT MONO (-7975 4200);
DISPLAY INVISIBLE (-7975 4200);
FORCEPROP 0 LAST CDS_SEC 1
J 2
(-7975 4200);
DISPLAY 1.021277 (-7975 4200);
DISPLAY INVISIBLE (-7975 4200);
FORCEADD OFFPAGE..1
(-7450 3925);
FORCEPROP 2 LAST $XR0 284 
J 0
(-7876 3925);
DISPLAY 0.638298 (-7876 3925);
PAINT MONO (-7876 3925);
FORCEPROP 1 LAST COMMENT_BODY TRUE
J 0
(-7325 3825);
DISPLAY 0.872340 (-7325 3825);
PAINT GREEN (-7325 3825);
DISPLAY INVISIBLE (-7325 3825);
FORCEPROP 1 LAST OFFPAGE TRUE
J 0
(-7125 3800);
DISPLAY 0.872340 (-7125 3800);
PAINT GREEN (-7125 3800);
DISPLAY INVISIBLE (-7125 3800);
FORCEPROP 2 LAST CDS_LIB standard
J 0
(-7450 3925);
DISPLAY INVISIBLE (-7450 3925);
FORCEPROP 2 LAST PATH I16
J 0
(-7875 3975);
DISPLAY 1.021277 (-7875 3975);
DISPLAY INVISIBLE (-7875 3975);
FORCEADD OFFPAGE..5
(-7450 4025);
FORCEPROP 2 LAST $XR4 284 
J 0
(-7705 4097);
DISPLAY 0.638298 (-7705 4097);
PAINT MONO (-7705 4097);
FORCEPROP 2 LAST $XR3 288 
J 0
(-7705 3953);
DISPLAY 0.638298 (-7705 3953);
PAINT MONO (-7705 3953);
FORCEPROP 2 LAST $XR2 287 
J 0
(-7705 4061);
DISPLAY 0.638298 (-7705 4061);
PAINT MONO (-7705 4061);
FORCEPROP 2 LAST $XR1 286 
J 0
(-7705 3989);
DISPLAY 0.638298 (-7705 3989);
PAINT MONO (-7705 3989);
FORCEPROP 2 LAST $XR0 285 
J 0
(-7705 4025);
DISPLAY 0.638298 (-7705 4025);
PAINT MONO (-7705 4025);
FORCEPROP 1 LAST COMMENT_BODY TRUE
J 0
(-7350 3950);
DISPLAY 0.872340 (-7350 3950);
PAINT GREEN (-7350 3950);
DISPLAY INVISIBLE (-7350 3950);
FORCEPROP 1 LAST OFFPAGE TRUE
J 0
(-7125 3900);
DISPLAY 0.872340 (-7125 3900);
PAINT GREEN (-7125 3900);
DISPLAY INVISIBLE (-7125 3900);
FORCEPROP 2 LAST CDS_LIB standard
J 0
(-7450 4025);
DISPLAY INVISIBLE (-7450 4025);
FORCEPROP 2 LAST PATH I17
J 0
(-7700 4150);
DISPLAY 1.021277 (-7700 4150);
DISPLAY INVISIBLE (-7700 4150);
FORCEADD Q_CAP..1
(-7125 2700);
FORCEPROP 1 LAST PART_NUMBER CH5222KEB01
J 0
(-7075 2575);
DISPLAY 0.617021 (-7075 2575);
PAINT BLUE (-7075 2575);
DISPLAY INVISIBLE (-7075 2575);
FORCEPROP 1 LAST MATERIAL X6S
J 0
(-7075 2625);
DISPLAY 0.617021 (-7075 2625);
PAINT SKYBLUE (-7075 2625);
FORCEPROP 1 LAST TOLERANCE 10%
J 0
(-7075 2675);
DISPLAY 0.617021 (-7075 2675);
PAINT SKYBLUE (-7075 2675);
FORCEPROP 1 LAST VALUE 2.2UF
J 0
(-7075 2775);
DISPLAY 0.617021 (-7075 2775);
PAINT SKYBLUE (-7075 2775);
FORCEPROP 1 LAST VOLTAGE 10V
J 0
(-7075 2725);
DISPLAY 0.617021 (-7075 2725);
PAINT SKYBLUE (-7075 2725);
FORCEPROP 1 LAST PACK_TYPE C0402
J 0
(-7075 2525);
DISPLAY 0.617021 (-7075 2525);
PAINT SKYBLUE (-7075 2525);
FORCEPROP 1 LAST LOCATION PC481_P1_8
J 0
(-7075 2825);
DISPLAY 0.617021 (-7075 2825);
PAINT AQUA (-7075 2825);
FORCEPROP 1 LASTPIN (-7125 2800) $PN 1
J 0
(-7115 2780);
DISPLAY 0.617021 (-7115 2780);
PAINT MONO (-7115 2780);
FORCEPROP 1 LASTPIN (-7125 2600) $PN 2
J 0
(-7115 2580);
DISPLAY 0.617021 (-7115 2580);
PAINT MONO (-7115 2580);
FORCEPROP 2 LAST CDS_LIB pure_quanta
J 0
(-7125 2700);
DISPLAY INVISIBLE (-7125 2700);
FORCEPROP 1 LAST PATH I18
J 0
(-7075 2850);
DISPLAY 0.978723 (-7075 2850);
PAINT WHITE (-7075 2850);
DISPLAY INVISIBLE (-7075 2850);
FORCEPROP 1 LAST LOCATION PC481_P1_8
J 0
(-7075 2875);
DISPLAY 1.021277 (-7075 2875);
PAINT AQUA (-7075 2875);
DISPLAY INVISIBLE (-7075 2875);
FORCEPROP 0 LAST $SEC 1
J 0
(-7075 2875);
DISPLAY 0.680851 (-7075 2875);
PAINT MONO (-7075 2875);
DISPLAY INVISIBLE (-7075 2875);
FORCEPROP 0 LAST CDS_SEC 1
J 0
(-7075 2875);
DISPLAY 1.021277 (-7075 2875);
DISPLAY INVISIBLE (-7075 2875);
FORCEADD UNIVERSAL_GND..1
(-7125 2475);
FORCEPROP 3 LASTPIN (-7125 2525) SIG_NAME GND\g
J 0
(-7115 2535);
DISPLAY 0.659574 (-7115 2535);
PAINT MONO (-7115 2535);
DISPLAY INVISIBLE (-7115 2535);
FORCEPROP 2 LAST CDS_LIB logical_power
J 0
(-7125 2475);
PAINT MONO (-7125 2475);
DISPLAY INVISIBLE (-7125 2475);
FORCEPROP 1 LAST HDL_POWER GND
J 1
(-7100 2400);
DISPLAY 0.872340 (-7100 2400);
PAINT GREEN (-7100 2400);
DISPLAY INVISIBLE (-7100 2400);
FORCEPROP 1 LAST PATH I19
J 0
(-7050 2475);
DISPLAY 0.872340 (-7050 2475);
PAINT AQUA (-7050 2475);
DISPLAY INVISIBLE (-7050 2475);
FORCEADD OFFPAGE..1
(-7475 1100);
FORCEPROP 2 LAST $XR0 284 
J 0
(-7901 1100);
DISPLAY 0.638298 (-7901 1100);
PAINT MONO (-7901 1100);
FORCEPROP 1 LAST COMMENT_BODY TRUE
J 0
(-7350 1000);
DISPLAY 0.872340 (-7350 1000);
PAINT GREEN (-7350 1000);
DISPLAY INVISIBLE (-7350 1000);
FORCEPROP 1 LAST OFFPAGE TRUE
J 0
(-7150 975);
DISPLAY 0.872340 (-7150 975);
PAINT GREEN (-7150 975);
DISPLAY INVISIBLE (-7150 975);
FORCEPROP 2 LAST CDS_LIB standard
J 0
(-7475 1100);
DISPLAY INVISIBLE (-7475 1100);
FORCEPROP 2 LAST PATH I2
J 0
(-7900 1150);
DISPLAY 1.021277 (-7900 1150);
DISPLAY INVISIBLE (-7900 1150);
FORCEADD ISL99390FRZTR5935..1
(-6000 4525);
FORCEPROP 1 LAST PART_NUMBER AL099390004
J 0
(-6300 5325);
DISPLAY 0.617021 (-6300 5325);
PAINT BLUE (-6300 5325);
DISPLAY INVISIBLE (-6300 5325);
FORCEPROP 2 LAST PART_TYPE SMLF
J 0
(-6300 5525);
DISPLAY 0.638298 (-6300 5525);
FORCEPROP 1 LAST MATERIAL IC
J 0
(-6300 5250);
DISPLAY 0.617021 (-6300 5250);
PAINT SKYBLUE (-6300 5250);
FORCEPROP 2 LAST VALUE ISL99390FRZ-TR5935
J 0
(-6300 5475);
DISPLAY 0.617021 (-6300 5475);
PAINT SKYBLUE (-6300 5475);
FORCEPROP 1 LAST LOCATION PU24_P1_7
J 0
(-6300 5400);
DISPLAY 0.617021 (-6300 5400);
PAINT AQUA (-6300 5400);
FORCEPROP 2 LASTPIN (-5600 4075) $PN 2
J 0
(-5590 4085);
DISPLAY 0.617021 (-5590 4085);
PAINT MONO (-5590 4085);
FORCEPROP 2 LASTPIN (-5600 4875) $PN 33
J 0
(-5590 4885);
DISPLAY 0.617021 (-5590 4885);
PAINT MONO (-5590 4885);
FORCEPROP 2 LASTPIN (-6450 4275) $PN 31
J 2
(-6460 4285);
DISPLAY 0.617021 (-6460 4285);
PAINT MONO (-6460 4285);
FORCEPROP 2 LASTPIN (-6450 4675) $PN 35
J 2
(-6460 4685);
DISPLAY 0.617021 (-6460 4685);
PAINT MONO (-6460 4685);
FORCEPROP 2 LASTPIN (-5600 4225) $PN 6
J 0
(-5590 4235);
DISPLAY 0.617021 (-5590 4235);
PAINT MONO (-5590 4235);
FORCEPROP 2 LASTPIN (-5600 4175) $PN 41
J 0
(-5590 4185);
DISPLAY 0.617021 (-5590 4185);
PAINT MONO (-5590 4185);
FORCEPROP 2 LASTPIN (-6450 4525) $PN 38
J 2
(-6460 4535);
DISPLAY 0.617021 (-6460 4535);
PAINT MONO (-6460 4535);
FORCEPROP 2 LASTPIN (-6450 4225) $PN 37
J 2
(-6460 4235);
DISPLAY 0.617021 (-6460 4235);
PAINT MONO (-6460 4235);
FORCEPROP 2 LASTPIN (-5600 4025) $PN 5
J 0
(-5590 4035);
DISPLAY 0.617021 (-5590 4035);
PAINT MONO (-5590 4035);
FORCEPROP 2 LASTPIN (-5600 3975) $PN 7_9-20_24
J 0
(-5590 3985);
DISPLAY 0.617021 (-5590 3985);
PAINT MONO (-5590 3985);
FORCEPROP 2 LASTPIN (-5600 3925) $PN 40
J 0
(-5590 3935);
DISPLAY 0.617021 (-5590 3935);
PAINT MONO (-5590 3935);
FORCEPROP 2 LASTPIN (-5600 4625) $PN 32
J 0
(-5590 4635);
DISPLAY 0.617021 (-5590 4635);
PAINT MONO (-5590 4635);
FORCEPROP 2 LASTPIN (-6450 5175) $PN 4
J 2
(-6460 5185);
DISPLAY 0.617021 (-6460 5185);
PAINT MONO (-6460 5185);
FORCEPROP 2 LASTPIN (-6450 3925) $PN 34
J 2
(-6460 3935);
DISPLAY 0.617021 (-6460 3935);
PAINT MONO (-6460 3935);
FORCEPROP 2 LASTPIN (-6450 4425) $PN 39
J 2
(-6460 4435);
DISPLAY 0.617021 (-6460 4435);
PAINT MONO (-6460 4435);
FORCEPROP 2 LASTPIN (-5600 4525) $PN 10_19
J 0
(-5590 4535);
DISPLAY 0.617021 (-5590 4535);
PAINT MONO (-5590 4535);
FORCEPROP 2 LASTPIN (-6450 4025) $PN 36
J 2
(-6460 4035);
DISPLAY 0.617021 (-6460 4035);
PAINT MONO (-6460 4035);
FORCEPROP 2 LASTPIN (-6450 4875) $PN 3
J 2
(-6460 4885);
DISPLAY 0.617021 (-6460 4885);
PAINT MONO (-6460 4885);
FORCEPROP 2 LASTPIN (-5600 5175) $PN 25_29
J 0
(-5590 5185);
DISPLAY 0.617021 (-5590 5185);
PAINT MONO (-5590 5185);
FORCEPROP 2 LASTPIN (-5600 5125) $PN 30
J 0
(-5590 5135);
DISPLAY 0.617021 (-5590 5135);
PAINT MONO (-5590 5135);
FORCEPROP 2 LASTPIN (-5600 4275) $PN 1
J 0
(-5590 4285);
DISPLAY 0.617021 (-5590 4285);
PAINT MONO (-5590 4285);
FORCEPROP 1 LAST NEEDS_NO_SIZE TRUE
J 0
(-6000 4525);
DISPLAY 0.723404 (-6000 4525);
PAINT GREEN (-6000 4525);
DISPLAY INVISIBLE (-6000 4525);
FORCEPROP 1 LAST CDS_LMAN_SYM_OUTLINE -300,700,250,-650
J 0
(-6000 4525);
DISPLAY 0.468085 (-6000 4525);
PAINT GREEN (-6000 4525);
DISPLAY INVISIBLE (-6000 4525);
FORCEPROP 2 LAST CDS_LIB pure_quanta
J 0
(-6000 4525);
DISPLAY INVISIBLE (-6000 4525);
FORCEPROP 1 LAST PATH I20
J 0
(-6000 4525);
DISPLAY 0.723404 (-6000 4525);
PAINT GREEN (-6000 4525);
DISPLAY INVISIBLE (-6000 4525);
FORCEPROP 2 LAST $SEC 1
J 0
(-6300 5450);
DISPLAY 0.680851 (-6300 5450);
PAINT MONO (-6300 5450);
DISPLAY INVISIBLE (-6300 5450);
FORCEPROP 2 LAST CDS_SEC 1
J 0
(-6300 5450);
DISPLAY 1.021277 (-6300 5450);
DISPLAY INVISIBLE (-6300 5450);
FORCEADD UNIVERSAL_GND..1
(-5375 975);
FORCEPROP 3 LASTPIN (-5375 1025) SIG_NAME GND\g
J 0
(-5365 1035);
DISPLAY 0.659574 (-5365 1035);
PAINT MONO (-5365 1035);
DISPLAY INVISIBLE (-5365 1035);
FORCEPROP 2 LAST CDS_LIB logical_power
J 0
(-5375 975);
PAINT MONO (-5375 975);
DISPLAY INVISIBLE (-5375 975);
FORCEPROP 1 LAST HDL_POWER GND
J 1
(-5350 900);
DISPLAY 0.872340 (-5350 900);
PAINT GREEN (-5350 900);
DISPLAY INVISIBLE (-5350 900);
FORCEPROP 1 LAST PATH I21
J 0
(-5300 975);
DISPLAY 0.872340 (-5300 975);
PAINT AQUA (-5300 975);
DISPLAY INVISIBLE (-5300 975);
FORCEADD UNIVERSAL_GND..1
(-4775 1325);
FORCEPROP 3 LASTPIN (-4775 1375) SIG_NAME GND\g
J 0
(-4765 1385);
DISPLAY 0.659574 (-4765 1385);
PAINT MONO (-4765 1385);
DISPLAY INVISIBLE (-4765 1385);
FORCEPROP 2 LAST CDS_LIB logical_power
J 0
(-4775 1325);
DISPLAY INVISIBLE (-4775 1325);
FORCEPROP 1 LAST HDL_POWER GND
J 1
(-4750 1250);
DISPLAY 0.872340 (-4750 1250);
PAINT GREEN (-4750 1250);
DISPLAY INVISIBLE (-4750 1250);
FORCEPROP 1 LAST PATH I22
J 0
(-4700 1325);
DISPLAY 0.872340 (-4700 1325);
PAINT AQUA (-4700 1325);
DISPLAY INVISIBLE (-4700 1325);
FORCEADD Q_INDUCTOR..1
R 2
(-4550 1475);
FORCEPROP 1 LAST PART_NUMBER CV+12^0EZ03
J 2
(-4425 1585);
DISPLAY 0.617021 (-4425 1585);
PAINT BLUE (-4425 1585);
DISPLAY INVISIBLE (-4425 1585);
FORCEPROP 2 LAST VALUE 120NH/69A
J 2
(-4425 1725);
DISPLAY 0.617021 (-4425 1725);
PAINT SKYBLUE (-4425 1725);
FORCEPROP 2 LAST PACK_TYPE SMLF
J 2
(-4425 1675);
DISPLAY 0.617021 (-4425 1675);
PAINT SKYBLUE (-4425 1675);
FORCEPROP 1 LAST MATERIAL IND
J 2
(-4425 1530);
DISPLAY 0.617021 (-4425 1530);
PAINT SKYBLUE (-4425 1530);
FORCEPROP 1 LAST LOCATION PL106
J 2
(-4425 1635);
DISPLAY 0.617021 (-4425 1635);
PAINT AQUA (-4425 1635);
FORCEPROP 0 LASTPIN (-4450 1450) $PN 1
J 0
(-4440 1460);
DISPLAY 0.617021 (-4440 1460);
PAINT MONO (-4440 1460);
FORCEPROP 0 LASTPIN (-4650 1450) $PN 2
J 2
(-4660 1460);
DISPLAY 0.617021 (-4660 1460);
PAINT MONO (-4660 1460);
FORCEPROP 1 LAST NEEDS_NO_SIZE TRUE
J 2
(-4550 1475);
DISPLAY 0.468085 (-4550 1475);
PAINT GREEN (-4550 1475);
DISPLAY INVISIBLE (-4550 1475);
FORCEPROP 2 LAST CDS_LIB pure_quanta
J 2
(-4550 1475);
DISPLAY INVISIBLE (-4550 1475);
FORCEPROP 1 LAST PATH I23
J 2
(-4625 1530);
DISPLAY 0.723404 (-4625 1530);
PAINT GREEN (-4625 1530);
DISPLAY INVISIBLE (-4625 1530);
FORCEPROP 0 LAST $SEC 1
J 2
(-4425 1775);
DISPLAY 0.680851 (-4425 1775);
PAINT MONO (-4425 1775);
DISPLAY INVISIBLE (-4425 1775);
FORCEPROP 0 LAST CDS_SEC 1
J 2
(-4425 1775);
DISPLAY 1.021277 (-4425 1775);
DISPLAY INVISIBLE (-4425 1775);
FORCEADD Q_CAP..1
(-5225 2600);
FORCEPROP 1 LAST PART_NUMBER TMP_QCH2336K1B12
J 0
(-5175 2450);
DISPLAY 0.617021 (-5175 2450);
PAINT BLUE (-5175 2450);
DISPLAY INVISIBLE (-5175 2450);
FORCEPROP 1 LAST MATERIAL X7R
J 0
(-5175 2550);
DISPLAY 0.617021 (-5175 2550);
PAINT SKYBLUE (-5175 2550);
FORCEPROP 1 LAST TOLERANCE 10%
J 0
(-5175 2600);
DISPLAY 0.617021 (-5175 2600);
PAINT SKYBLUE (-5175 2600);
FORCEPROP 1 LAST PACK_TYPE 0402
J 0
(-5175 2500);
DISPLAY 0.617021 (-5175 2500);
PAINT SKYBLUE (-5175 2500);
FORCEPROP 1 LAST VOLTAGE 50V
J 0
(-5175 2650);
DISPLAY 0.617021 (-5175 2650);
PAINT SKYBLUE (-5175 2650);
FORCEPROP 1 LAST VALUE 3300PF
J 0
(-5175 2700);
DISPLAY 0.617021 (-5175 2700);
PAINT SKYBLUE (-5175 2700);
FORCEPROP 1 LAST LOCATION PC483_P1_8
J 0
(-5175 2750);
DISPLAY 0.617021 (-5175 2750);
PAINT AQUA (-5175 2750);
FORCEPROP 1 LASTPIN (-5225 2700) $PN 1
J 0
(-5215 2680);
DISPLAY 0.617021 (-5215 2680);
PAINT MONO (-5215 2680);
FORCEPROP 1 LASTPIN (-5225 2500) $PN 2
J 0
(-5215 2480);
DISPLAY 0.617021 (-5215 2480);
PAINT MONO (-5215 2480);
FORCEPROP 2 LAST CDS_LIB pure_quanta
J 0
(-5225 2600);
DISPLAY INVISIBLE (-5225 2600);
FORCEPROP 1 LAST PATH I24
J 0
(-5175 2750);
DISPLAY 0.978723 (-5175 2750);
PAINT WHITE (-5175 2750);
DISPLAY INVISIBLE (-5175 2750);
FORCEPROP 1 LAST LOCATION PC483_P1_8
J 0
(-5175 2800);
DISPLAY 1.021277 (-5175 2800);
PAINT AQUA (-5175 2800);
DISPLAY INVISIBLE (-5175 2800);
FORCEPROP 0 LAST $SEC 1
J 0
(-5175 2800);
DISPLAY 0.680851 (-5175 2800);
PAINT MONO (-5175 2800);
DISPLAY INVISIBLE (-5175 2800);
FORCEPROP 0 LAST CDS_SEC 1
J 0
(-5175 2800);
DISPLAY 1.021277 (-5175 2800);
DISPLAY INVISIBLE (-5175 2800);
FORCEADD UNIVERSAL_GND..1
(-5350 3800);
FORCEPROP 3 LASTPIN (-5350 3850) SIG_NAME GND\g
J 0
(-5340 3860);
DISPLAY 0.659574 (-5340 3860);
PAINT MONO (-5340 3860);
DISPLAY INVISIBLE (-5340 3860);
FORCEPROP 2 LAST CDS_LIB logical_power
J 0
(-5350 3800);
PAINT MONO (-5350 3800);
DISPLAY INVISIBLE (-5350 3800);
FORCEPROP 1 LAST HDL_POWER GND
J 1
(-5325 3725);
DISPLAY 0.872340 (-5325 3725);
PAINT GREEN (-5325 3725);
DISPLAY INVISIBLE (-5325 3725);
FORCEPROP 1 LAST PATH I25
J 0
(-5275 3800);
DISPLAY 0.872340 (-5275 3800);
PAINT AQUA (-5275 3800);
DISPLAY INVISIBLE (-5275 3800);
FORCEADD Q_RES..1
(-4775 2150);
FORCEPROP 1 LAST PART_NUMBER CS-3302FB01
J 0
(-4875 2200);
DISPLAY 0.617021 (-4875 2200);
PAINT BLUE (-4875 2200);
DISPLAY INVISIBLE (-4875 2200);
FORCEPROP 1 LAST MATERIAL CHIP
J 0
(-4875 2250);
DISPLAY 0.617021 (-4875 2250);
PAINT SKYBLUE (-4875 2250);
FORCEPROP 1 LAST TOLERANCE 1%
J 0
(-4625 2150);
DISPLAY 0.617021 (-4625 2150);
PAINT SKYBLUE (-4625 2150);
FORCEPROP 1 LAST VALUE 3.3
J 2
(-4650 2150);
DISPLAY 0.617021 (-4650 2150);
PAINT SKYBLUE (-4650 2150);
FORCEPROP 1 LAST PACK_TYPE 0402LF
J 0
(-4875 2225);
DISPLAY 0.617021 (-4875 2225);
PAINT SKYBLUE (-4875 2225);
FORCEPROP 1 LAST WATTAGE 1/16W
J 2
(-4650 2225);
DISPLAY 0.617021 (-4650 2225);
PAINT SKYBLUE (-4650 2225);
FORCEPROP 1 LAST LOCATION PR1792
J 0
(-4975 2150);
DISPLAY 0.617021 (-4975 2150);
PAINT AQUA (-4975 2150);
FORCEPROP 1 LASTPIN (-4875 2150) $PN 1
J 0
(-4863 2162);
DISPLAY 0.617021 (-4863 2162);
FORCEPROP 1 LASTPIN (-4675 2150) $PN 2
J 0
(-4713 2162);
DISPLAY 0.617021 (-4713 2162);
FORCEPROP 2 LAST CDS_LIB pure_quanta
J 0
(-4775 2150);
PAINT MONO (-4775 2150);
DISPLAY INVISIBLE (-4775 2150);
FORCEPROP 1 LAST PATH I26
J 0
(-4825 2300);
DISPLAY 0.978723 (-4825 2300);
PAINT WHITE (-4825 2300);
DISPLAY INVISIBLE (-4825 2300);
FORCEPROP 2 LAST $SEC 1
J 0
(-4825 2350);
DISPLAY 0.680851 (-4825 2350);
PAINT MONO (-4825 2350);
DISPLAY INVISIBLE (-4825 2350);
FORCEPROP 2 LAST CDS_SEC 1
J 0
(-4825 2350);
DISPLAY 1.021277 (-4825 2350);
DISPLAY INVISIBLE (-4825 2350);
FORCEADD Q_CAP..1
(-4825 2600);
FORCEPROP 1 LAST PART_NUMBER CH5103KEB01
J 0
(-4775 2450);
DISPLAY 0.617021 (-4775 2450);
PAINT BLUE (-4775 2450);
DISPLAY INVISIBLE (-4775 2450);
FORCEPROP 1 LAST MATERIAL X6S
J 0
(-4775 2550);
DISPLAY 0.617021 (-4775 2550);
PAINT SKYBLUE (-4775 2550);
FORCEPROP 1 LAST TOLERANCE 10%
J 0
(-4775 2600);
DISPLAY 0.617021 (-4775 2600);
PAINT SKYBLUE (-4775 2600);
FORCEPROP 1 LAST VOLTAGE 16V
J 0
(-4775 2650);
DISPLAY 0.617021 (-4775 2650);
PAINT SKYBLUE (-4775 2650);
FORCEPROP 1 LAST PACK_TYPE C0402
J 0
(-4775 2500);
DISPLAY 0.617021 (-4775 2500);
PAINT SKYBLUE (-4775 2500);
FORCEPROP 1 LAST VALUE 1UF
J 0
(-4775 2700);
DISPLAY 0.617021 (-4775 2700);
PAINT SKYBLUE (-4775 2700);
FORCEPROP 1 LAST LOCATION PC485_P1_8
J 0
(-4775 2750);
DISPLAY 0.617021 (-4775 2750);
PAINT AQUA (-4775 2750);
FORCEPROP 1 LASTPIN (-4825 2700) $PN 1
J 0
(-4815 2680);
DISPLAY 0.617021 (-4815 2680);
PAINT MONO (-4815 2680);
FORCEPROP 1 LASTPIN (-4825 2500) $PN 2
J 0
(-4815 2480);
DISPLAY 0.617021 (-4815 2480);
PAINT MONO (-4815 2480);
FORCEPROP 2 LAST CDS_LIB pure_quanta
J 0
(-4825 2600);
DISPLAY INVISIBLE (-4825 2600);
FORCEPROP 1 LAST PATH I27
J 0
(-4775 2750);
DISPLAY 0.978723 (-4775 2750);
PAINT WHITE (-4775 2750);
DISPLAY INVISIBLE (-4775 2750);
FORCEPROP 1 LAST LOCATION PC485_P1_8
J 0
(-4775 2800);
DISPLAY 1.021277 (-4775 2800);
PAINT AQUA (-4775 2800);
DISPLAY INVISIBLE (-4775 2800);
FORCEPROP 0 LAST $SEC 1
J 0
(-4775 2800);
DISPLAY 0.680851 (-4775 2800);
PAINT MONO (-4775 2800);
DISPLAY INVISIBLE (-4775 2800);
FORCEPROP 0 LAST CDS_SEC 1
J 0
(-4775 2800);
DISPLAY 1.021277 (-4775 2800);
DISPLAY INVISIBLE (-4775 2800);
FORCEADD Q_CAP..1
(-4425 2600);
FORCEPROP 1 LAST PART_NUMBER CH6223MEA01
J 0
(-4375 2450);
DISPLAY 0.617021 (-4375 2450);
PAINT BLUE (-4375 2450);
DISPLAY INVISIBLE (-4375 2450);
FORCEPROP 1 LAST MATERIAL X6S
J 0
(-4375 2550);
DISPLAY 0.617021 (-4375 2550);
PAINT SKYBLUE (-4375 2550);
FORCEPROP 1 LAST TOLERANCE 20%
J 0
(-4375 2600);
DISPLAY 0.617021 (-4375 2600);
PAINT SKYBLUE (-4375 2600);
FORCEPROP 1 LAST VALUE 22UF
J 0
(-4375 2700);
DISPLAY 0.617021 (-4375 2700);
PAINT SKYBLUE (-4375 2700);
FORCEPROP 1 LAST VOLTAGE 16V
J 0
(-4375 2650);
DISPLAY 0.617021 (-4375 2650);
PAINT SKYBLUE (-4375 2650);
FORCEPROP 1 LAST PACK_TYPE C0805
J 0
(-4375 2500);
DISPLAY 0.617021 (-4375 2500);
PAINT SKYBLUE (-4375 2500);
FORCEPROP 1 LAST LOCATION PC489_P1_8
J 0
(-4375 2750);
DISPLAY 0.617021 (-4375 2750);
PAINT AQUA (-4375 2750);
FORCEPROP 1 LASTPIN (-4425 2700) $PN 1
J 0
(-4415 2680);
DISPLAY 0.617021 (-4415 2680);
PAINT MONO (-4415 2680);
FORCEPROP 1 LASTPIN (-4425 2500) $PN 2
J 0
(-4415 2480);
DISPLAY 0.617021 (-4415 2480);
PAINT MONO (-4415 2480);
FORCEPROP 2 LAST CDS_LIB pure_quanta
J 0
(-4425 2600);
DISPLAY INVISIBLE (-4425 2600);
FORCEPROP 1 LAST PATH I28
J 0
(-4375 2750);
DISPLAY 0.978723 (-4375 2750);
PAINT WHITE (-4375 2750);
DISPLAY INVISIBLE (-4375 2750);
FORCEPROP 1 LAST LOCATION PC489_P1_8
J 0
(-4375 2800);
DISPLAY 1.021277 (-4375 2800);
PAINT AQUA (-4375 2800);
DISPLAY INVISIBLE (-4375 2800);
FORCEPROP 0 LAST $SEC 1
J 0
(-4375 2800);
DISPLAY 0.680851 (-4375 2800);
PAINT MONO (-4375 2800);
DISPLAY INVISIBLE (-4375 2800);
FORCEPROP 0 LAST CDS_SEC 1
J 0
(-4375 2800);
DISPLAY 1.021277 (-4375 2800);
DISPLAY INVISIBLE (-4375 2800);
FORCEADD UNIVERSAL_GND..1
(-8025 4250);
FORCEPROP 3 LASTPIN (-8025 4300) SIG_NAME GND\g
J 0
(-8015 4310);
DISPLAY 0.659574 (-8015 4310);
PAINT MONO (-8015 4310);
DISPLAY INVISIBLE (-8015 4310);
FORCEPROP 2 LAST CDS_LIB logical_power
J 0
(-8025 4250);
PAINT MONO (-8025 4250);
DISPLAY INVISIBLE (-8025 4250);
FORCEPROP 1 LAST HDL_POWER GND
J 1
(-8000 4175);
DISPLAY 0.872340 (-8000 4175);
PAINT GREEN (-8000 4175);
DISPLAY INVISIBLE (-8000 4175);
FORCEPROP 1 LAST PATH I29
J 0
(-7950 4250);
DISPLAY 0.872340 (-7950 4250);
PAINT AQUA (-7950 4250);
DISPLAY INVISIBLE (-7950 4250);
FORCEADD Q_RES..2
R 2
(-7950 1200);
FORCEPROP 1 LAST PART_NUMBER CS28872FB01
J 2
(-8000 1075);
DISPLAY 0.617021 (-8000 1075);
PAINT BLUE (-8000 1075);
DISPLAY INVISIBLE (-8000 1075);
FORCEPROP 1 LAST WATTAGE 1/16W
J 2
(-8000 1175);
DISPLAY 0.617021 (-8000 1175);
PAINT SKYBLUE (-8000 1175);
FORCEPROP 1 LAST MATERIAL EMPTY
J 2
(-8000 1125);
DISPLAY 0.617021 (-8000 1125);
PAINT RED (-8000 1125);
FORCEPROP 1 LAST TOLERANCE 1%
J 2
(-8005 1225);
DISPLAY 0.617021 (-8005 1225);
PAINT SKYBLUE (-8005 1225);
FORCEPROP 1 LAST VALUE 8.87K
J 2
(-8005 1275);
DISPLAY 0.617021 (-8005 1275);
PAINT SKYBLUE (-8005 1275);
FORCEPROP 1 LAST PACK_TYPE 0402LF
J 2
(-8000 1025);
DISPLAY 0.617021 (-8000 1025);
PAINT SKYBLUE (-8000 1025);
FORCEPROP 1 LAST LOCATION PR285
J 2
(-7995 1325);
DISPLAY 0.617021 (-7995 1325);
PAINT AQUA (-7995 1325);
FORCEPROP 1 LASTPIN (-7950 1300) $PN 1
J 2
(-7955 1262);
DISPLAY 0.617021 (-7955 1262);
PAINT MONO (-7955 1262);
FORCEPROP 1 LASTPIN (-7950 1100) $PN 2
J 2
(-7955 1110);
DISPLAY 0.617021 (-7955 1110);
PAINT MONO (-7955 1110);
FORCEPROP 2 LAST CDS_LIB pure_quanta
J 2
(-7950 1200);
DISPLAY INVISIBLE (-7950 1200);
FORCEPROP 1 LAST PATH I3
J 2
(-8000 1375);
DISPLAY 0.978723 (-8000 1375);
PAINT WHITE (-8000 1375);
DISPLAY INVISIBLE (-8000 1375);
FORCEPROP 1 LAST LOCATION PR285
J 2
(-8000 1375);
DISPLAY 1.021277 (-8000 1375);
PAINT AQUA (-8000 1375);
DISPLAY INVISIBLE (-8000 1375);
FORCEPROP 0 LAST $SEC 1
J 2
(-8000 1375);
DISPLAY 0.680851 (-8000 1375);
PAINT MONO (-8000 1375);
DISPLAY INVISIBLE (-8000 1375);
FORCEPROP 0 LAST CDS_SEC 1
J 2
(-8000 1375);
DISPLAY 1.021277 (-8000 1375);
DISPLAY INVISIBLE (-8000 1375);
FORCEADD OFFPAGE..1
(-7450 4425);
FORCEPROP 2 LAST $XR6 290 
J 0
(-8452 4425);
DISPLAY 0.638298 (-8452 4425);
PAINT MONO (-8452 4425);
FORCEPROP 2 LAST $XR5 289 
J 0
(-8332 4425);
DISPLAY 0.638298 (-8332 4425);
PAINT MONO (-8332 4425);
FORCEPROP 2 LAST $XR4 288 
J 0
(-8212 4425);
DISPLAY 0.638298 (-8212 4425);
PAINT MONO (-8212 4425);
FORCEPROP 2 LAST $XR3 287 
J 0
(-8092 4425);
DISPLAY 0.638298 (-8092 4425);
PAINT MONO (-8092 4425);
FORCEPROP 2 LAST $XR2 286 
J 0
(-7972 4425);
DISPLAY 0.638298 (-7972 4425);
PAINT MONO (-7972 4425);
FORCEPROP 2 LAST $XR1 285 
J 0
(-7852 4425);
DISPLAY 0.638298 (-7852 4425);
PAINT MONO (-7852 4425);
FORCEPROP 2 LAST $XR0 284 
J 0
(-7732 4425);
DISPLAY 0.638298 (-7732 4425);
PAINT MONO (-7732 4425);
FORCEPROP 1 LAST COMMENT_BODY TRUE
J 0
(-7325 4325);
DISPLAY 0.872340 (-7325 4325);
PAINT GREEN (-7325 4325);
DISPLAY INVISIBLE (-7325 4325);
FORCEPROP 1 LAST OFFPAGE TRUE
J 0
(-7125 4300);
DISPLAY 0.872340 (-7125 4300);
PAINT GREEN (-7125 4300);
DISPLAY INVISIBLE (-7125 4300);
FORCEPROP 2 LAST CDS_LIB standard
J 0
(-7450 4425);
DISPLAY INVISIBLE (-7450 4425);
FORCEPROP 2 LAST PATH I30
J 0
(-7725 4475);
DISPLAY 1.021277 (-7725 4475);
DISPLAY INVISIBLE (-7725 4475);
FORCEADD OFFPAGE..5
(-7450 4525);
FORCEPROP 2 LAST $XR0 284 
J 0
(-7705 4525);
DISPLAY 0.638298 (-7705 4525);
PAINT MONO (-7705 4525);
FORCEPROP 1 LAST COMMENT_BODY TRUE
J 0
(-7350 4450);
DISPLAY 0.872340 (-7350 4450);
PAINT GREEN (-7350 4450);
DISPLAY INVISIBLE (-7350 4450);
FORCEPROP 1 LAST OFFPAGE TRUE
J 0
(-7125 4400);
DISPLAY 0.872340 (-7125 4400);
PAINT GREEN (-7125 4400);
DISPLAY INVISIBLE (-7125 4400);
FORCEPROP 2 LAST CDS_LIB standard
J 0
(-7450 4525);
DISPLAY INVISIBLE (-7450 4525);
FORCEPROP 2 LAST PATH I31
J 0
(-7700 4575);
DISPLAY 1.021277 (-7700 4575);
DISPLAY INVISIBLE (-7700 4575);
FORCEADD Q_CAP..2
(-7200 4325);
FORCEPROP 1 LAST PART_NUMBER CH4104K1B00
J 1
(-6975 4350);
DISPLAY 0.617021 (-6975 4350);
PAINT BLUE (-6975 4350);
DISPLAY INVISIBLE (-6975 4350);
FORCEPROP 1 LAST MATERIAL X7R
J 0
(-6825 4350);
DISPLAY 0.617021 (-6825 4350);
PAINT SKYBLUE (-6825 4350);
FORCEPROP 1 LAST TOLERANCE 10%
J 2
(-6675 4350);
DISPLAY 0.617021 (-6675 4350);
PAINT SKYBLUE (-6675 4350);
FORCEPROP 1 LAST VALUE 0.1UF
J 2
(-6975 4325);
DISPLAY 0.617021 (-6975 4325);
PAINT SKYBLUE (-6975 4325);
FORCEPROP 1 LAST VOLTAGE 25V
J 0
(-6950 4325);
DISPLAY 0.617021 (-6950 4325);
PAINT SKYBLUE (-6950 4325);
FORCEPROP 1 LAST PACK_TYPE 0402
J 1
(-6825 4325);
DISPLAY 0.617021 (-6825 4325);
PAINT SKYBLUE (-6825 4325);
FORCEPROP 1 LAST LOCATION PC1363
J 1
(-7400 4325);
DISPLAY 0.617021 (-7400 4325);
PAINT AQUA (-7400 4325);
FORCEPROP 1 LASTPIN (-7300 4325) $PN 1
J 0
(-7310 4340);
DISPLAY 0.617021 (-7310 4340);
FORCEPROP 1 LASTPIN (-7100 4325) $PN 2
J 0
(-7115 4340);
DISPLAY 0.617021 (-7115 4340);
FORCEPROP 2 LAST CDS_LIB pure_quanta
J 0
(-7200 4325);
PAINT MONO (-7200 4325);
DISPLAY INVISIBLE (-7200 4325);
FORCEPROP 1 LAST PATH I32
J 0
(-7200 4525);
DISPLAY 0.978723 (-7200 4525);
PAINT WHITE (-7200 4525);
DISPLAY INVISIBLE (-7200 4525);
FORCEPROP 2 LAST $SEC 1
J 0
(-7200 4575);
DISPLAY 0.680851 (-7200 4575);
PAINT MONO (-7200 4575);
DISPLAY INVISIBLE (-7200 4575);
FORCEPROP 2 LAST CDS_SEC 1
J 0
(-7200 4575);
DISPLAY 1.021277 (-7200 4575);
DISPLAY INVISIBLE (-7200 4575);
FORCEADD UNIVERSAL_GND..1
(-7525 4775);
FORCEPROP 3 LASTPIN (-7525 4825) SIG_NAME GND\g
J 0
(-7515 4835);
DISPLAY 0.659574 (-7515 4835);
PAINT MONO (-7515 4835);
DISPLAY INVISIBLE (-7515 4835);
FORCEPROP 2 LAST CDS_LIB logical_power
J 0
(-7525 4775);
PAINT MONO (-7525 4775);
DISPLAY INVISIBLE (-7525 4775);
FORCEPROP 1 LAST HDL_POWER GND
J 1
(-7500 4700);
DISPLAY 0.872340 (-7500 4700);
PAINT GREEN (-7500 4700);
DISPLAY INVISIBLE (-7500 4700);
FORCEPROP 1 LAST PATH I33
J 0
(-7450 4775);
DISPLAY 0.872340 (-7450 4775);
PAINT AQUA (-7450 4775);
DISPLAY INVISIBLE (-7450 4775);
FORCEADD Q_CAP..1
(-7525 5025);
FORCEPROP 1 LAST PART_NUMBER CH5222KEB01
J 0
(-7475 4850);
DISPLAY 0.617021 (-7475 4850);
PAINT BLUE (-7475 4850);
DISPLAY INVISIBLE (-7475 4850);
FORCEPROP 1 LAST MATERIAL X6S
J 0
(-7475 4950);
DISPLAY 0.617021 (-7475 4950);
PAINT SKYBLUE (-7475 4950);
FORCEPROP 1 LAST TOLERANCE 10%
J 0
(-7475 5000);
DISPLAY 0.617021 (-7475 5000);
PAINT SKYBLUE (-7475 5000);
FORCEPROP 1 LAST VALUE 2.2UF
J 0
(-7475 5100);
DISPLAY 0.617021 (-7475 5100);
PAINT SKYBLUE (-7475 5100);
FORCEPROP 1 LAST VOLTAGE 10V
J 0
(-7475 5050);
DISPLAY 0.617021 (-7475 5050);
PAINT SKYBLUE (-7475 5050);
FORCEPROP 1 LAST PACK_TYPE C0402
J 0
(-7475 4900);
DISPLAY 0.617021 (-7475 4900);
PAINT SKYBLUE (-7475 4900);
FORCEPROP 1 LAST LOCATION PC480
J 0
(-7475 5150);
DISPLAY 0.617021 (-7475 5150);
PAINT AQUA (-7475 5150);
FORCEPROP 1 LASTPIN (-7525 5125) $PN 1
J 0
(-7515 5105);
DISPLAY 0.617021 (-7515 5105);
PAINT MONO (-7515 5105);
FORCEPROP 1 LASTPIN (-7525 4925) $PN 2
J 0
(-7515 4905);
DISPLAY 0.617021 (-7515 4905);
PAINT MONO (-7515 4905);
FORCEPROP 2 LAST CDS_LIB pure_quanta
J 0
(-7525 5025);
DISPLAY INVISIBLE (-7525 5025);
FORCEPROP 1 LAST PATH I34
J 0
(-7475 5175);
DISPLAY 0.978723 (-7475 5175);
PAINT WHITE (-7475 5175);
DISPLAY INVISIBLE (-7475 5175);
FORCEPROP 1 LAST LOCATION PC480
J 0
(-7475 5200);
DISPLAY 1.021277 (-7475 5200);
PAINT AQUA (-7475 5200);
DISPLAY INVISIBLE (-7475 5200);
FORCEPROP 0 LAST $SEC 1
J 0
(-7475 5200);
DISPLAY 0.680851 (-7475 5200);
PAINT MONO (-7475 5200);
DISPLAY INVISIBLE (-7475 5200);
FORCEPROP 0 LAST CDS_SEC 1
J 0
(-7475 5200);
DISPLAY 1.021277 (-7475 5200);
DISPLAY INVISIBLE (-7475 5200);
FORCEADD VCC15..1
(-7525 5850);
FORCEPROP 3 LASTPIN (-7525 5800) SIG_NAME PVCCIN_CPU1_PVCC\g
J 0
(-7515 5810);
DISPLAY 0.659574 (-7515 5810);
PAINT MONO (-7515 5810);
DISPLAY INVISIBLE (-7515 5810);
FORCEPROP 1 LAST HDL_POWER PVCCIN_CPU1_PVCC
J 1
(-7525 5900);
DISPLAY 0.617021 (-7525 5900);
PAINT GREEN (-7525 5900);
FORCEPROP 2 LAST CDS_LIB logical_power
J 0
(-7525 5850);
DISPLAY INVISIBLE (-7525 5850);
FORCEPROP 1 LAST PATH I35
J 0
(-7475 5875);
DISPLAY 0.872340 (-7475 5875);
PAINT AQUA (-7475 5875);
DISPLAY INVISIBLE (-7475 5875);
FORCEADD UNIVERSAL_GND..1
(-7100 5300);
FORCEPROP 3 LASTPIN (-7100 5350) SIG_NAME GND\g
J 0
(-7090 5360);
DISPLAY 0.659574 (-7090 5360);
PAINT MONO (-7090 5360);
DISPLAY INVISIBLE (-7090 5360);
FORCEPROP 2 LAST CDS_LIB logical_power
J 0
(-7100 5300);
PAINT MONO (-7100 5300);
DISPLAY INVISIBLE (-7100 5300);
FORCEPROP 1 LAST HDL_POWER GND
J 1
(-7075 5225);
DISPLAY 0.872340 (-7075 5225);
PAINT GREEN (-7075 5225);
DISPLAY INVISIBLE (-7075 5225);
FORCEPROP 1 LAST PATH I36
J 0
(-7025 5300);
DISPLAY 0.872340 (-7025 5300);
PAINT AQUA (-7025 5300);
DISPLAY INVISIBLE (-7025 5300);
FORCEADD Q_CAP..1
(-5200 5425);
FORCEPROP 1 LAST PART_NUMBER TMP_QCH2336K1B12
J 0
(-5150 5275);
DISPLAY 0.617021 (-5150 5275);
PAINT BLUE (-5150 5275);
DISPLAY INVISIBLE (-5150 5275);
FORCEPROP 1 LAST MATERIAL X7R
J 0
(-5150 5375);
DISPLAY 0.617021 (-5150 5375);
PAINT SKYBLUE (-5150 5375);
FORCEPROP 1 LAST TOLERANCE 10%
J 0
(-5150 5425);
DISPLAY 0.617021 (-5150 5425);
PAINT SKYBLUE (-5150 5425);
FORCEPROP 1 LAST VALUE 3300PF
J 0
(-5150 5525);
DISPLAY 0.617021 (-5150 5525);
PAINT SKYBLUE (-5150 5525);
FORCEPROP 1 LAST VOLTAGE 50V
J 0
(-5150 5475);
DISPLAY 0.617021 (-5150 5475);
PAINT SKYBLUE (-5150 5475);
FORCEPROP 1 LAST PACK_TYPE 0402
J 0
(-5150 5325);
DISPLAY 0.617021 (-5150 5325);
PAINT SKYBLUE (-5150 5325);
FORCEPROP 1 LAST LOCATION PC484_P1_7
J 0
(-5150 5575);
DISPLAY 0.617021 (-5150 5575);
PAINT AQUA (-5150 5575);
FORCEPROP 1 LASTPIN (-5200 5525) $PN 1
J 0
(-5190 5505);
DISPLAY 0.617021 (-5190 5505);
PAINT MONO (-5190 5505);
FORCEPROP 1 LASTPIN (-5200 5325) $PN 2
J 0
(-5190 5305);
DISPLAY 0.617021 (-5190 5305);
PAINT MONO (-5190 5305);
FORCEPROP 2 LAST CDS_LIB pure_quanta
J 0
(-5200 5425);
DISPLAY INVISIBLE (-5200 5425);
FORCEPROP 1 LAST PATH I37
J 0
(-5150 5575);
DISPLAY 0.978723 (-5150 5575);
PAINT WHITE (-5150 5575);
DISPLAY INVISIBLE (-5150 5575);
FORCEPROP 1 LAST LOCATION PC484_P1_7
J 0
(-5150 5625);
DISPLAY 1.021277 (-5150 5625);
PAINT AQUA (-5150 5625);
DISPLAY INVISIBLE (-5150 5625);
FORCEPROP 0 LAST $SEC 1
J 0
(-5150 5625);
DISPLAY 0.680851 (-5150 5625);
PAINT MONO (-5150 5625);
DISPLAY INVISIBLE (-5150 5625);
FORCEPROP 0 LAST CDS_SEC 1
J 0
(-5150 5625);
DISPLAY 1.021277 (-5150 5625);
DISPLAY INVISIBLE (-5150 5625);
FORCEADD OFFPAGE..6
(-4525 4275);
FORCEPROP 2 LAST $XR0 287 
J 0
(-4835 4275);
DISPLAY 0.638298 (-4835 4275);
PAINT MONO (-4835 4275);
FORCEPROP 2 LAST CDS_LIB standard
J 0
(-4525 4275);
DISPLAY INVISIBLE (-4525 4275);
FORCEPROP 1 LAST OFFPAGE TRUE
J 0
(-4200 4150);
DISPLAY 0.872340 (-4200 4150);
PAINT GREEN (-4200 4150);
DISPLAY INVISIBLE (-4200 4150);
FORCEPROP 1 LAST COMMENT_BODY TRUE
J 0
(-4425 4200);
DISPLAY 0.872340 (-4425 4200);
PAINT GREEN (-4425 4200);
DISPLAY INVISIBLE (-4425 4200);
FORCEPROP 2 LAST PATH I38
J 0
(-4825 4325);
DISPLAY 1.021277 (-4825 4325);
DISPLAY INVISIBLE (-4825 4325);
FORCEADD Q_RES..1
(-4750 4975);
FORCEPROP 1 LAST PART_NUMBER CS-3302FB01
J 0
(-4850 5025);
DISPLAY 0.617021 (-4850 5025);
PAINT BLUE (-4850 5025);
DISPLAY INVISIBLE (-4850 5025);
FORCEPROP 1 LAST WATTAGE 1/16W
J 2
(-4625 5050);
DISPLAY 0.617021 (-4625 5050);
PAINT SKYBLUE (-4625 5050);
FORCEPROP 1 LAST MATERIAL CHIP
J 0
(-4850 5075);
DISPLAY 0.617021 (-4850 5075);
PAINT SKYBLUE (-4850 5075);
FORCEPROP 1 LAST TOLERANCE 1%
J 0
(-4600 4975);
DISPLAY 0.617021 (-4600 4975);
PAINT SKYBLUE (-4600 4975);
FORCEPROP 1 LAST VALUE 3.3
J 2
(-4625 4975);
DISPLAY 0.617021 (-4625 4975);
PAINT SKYBLUE (-4625 4975);
FORCEPROP 1 LAST PACK_TYPE 0402LF
J 0
(-4850 5050);
DISPLAY 0.617021 (-4850 5050);
PAINT SKYBLUE (-4850 5050);
FORCEPROP 1 LAST LOCATION PR1793
J 0
(-4950 4975);
DISPLAY 0.617021 (-4950 4975);
PAINT AQUA (-4950 4975);
FORCEPROP 1 LASTPIN (-4850 4975) $PN 1
J 0
(-4838 4987);
DISPLAY 0.617021 (-4838 4987);
FORCEPROP 1 LASTPIN (-4650 4975) $PN 2
J 0
(-4688 4987);
DISPLAY 0.617021 (-4688 4987);
FORCEPROP 2 LAST CDS_LIB pure_quanta
J 0
(-4750 4975);
PAINT MONO (-4750 4975);
DISPLAY INVISIBLE (-4750 4975);
FORCEPROP 1 LAST PATH I39
J 0
(-4800 5125);
DISPLAY 0.978723 (-4800 5125);
PAINT WHITE (-4800 5125);
DISPLAY INVISIBLE (-4800 5125);
FORCEPROP 2 LAST $SEC 1
J 0
(-4800 5175);
DISPLAY 0.680851 (-4800 5175);
PAINT MONO (-4800 5175);
DISPLAY INVISIBLE (-4800 5175);
FORCEPROP 2 LAST CDS_SEC 1
J 0
(-4800 5175);
DISPLAY 1.021277 (-4800 5175);
DISPLAY INVISIBLE (-4800 5175);
FORCEADD UNIVERSAL_GND..1
(-8050 1425);
FORCEPROP 3 LASTPIN (-8050 1475) SIG_NAME GND\g
J 0
(-8040 1485);
DISPLAY 0.659574 (-8040 1485);
PAINT MONO (-8040 1485);
DISPLAY INVISIBLE (-8040 1485);
FORCEPROP 2 LAST CDS_LIB logical_power
J 0
(-8050 1425);
PAINT MONO (-8050 1425);
DISPLAY INVISIBLE (-8050 1425);
FORCEPROP 1 LAST HDL_POWER GND
J 1
(-8025 1350);
DISPLAY 0.872340 (-8025 1350);
PAINT GREEN (-8025 1350);
DISPLAY INVISIBLE (-8025 1350);
FORCEPROP 1 LAST PATH I4
J 0
(-7975 1425);
DISPLAY 0.872340 (-7975 1425);
PAINT AQUA (-7975 1425);
DISPLAY INVISIBLE (-7975 1425);
FORCEADD Q_CAP..1
(-4800 5425);
FORCEPROP 1 LAST PART_NUMBER CH5103KEB01
J 0
(-4750 5275);
DISPLAY 0.617021 (-4750 5275);
PAINT BLUE (-4750 5275);
DISPLAY INVISIBLE (-4750 5275);
FORCEPROP 1 LAST MATERIAL X6S
J 0
(-4750 5375);
DISPLAY 0.617021 (-4750 5375);
PAINT SKYBLUE (-4750 5375);
FORCEPROP 1 LAST TOLERANCE 10%
J 0
(-4750 5425);
DISPLAY 0.617021 (-4750 5425);
PAINT SKYBLUE (-4750 5425);
FORCEPROP 1 LAST VALUE 1UF
J 0
(-4750 5525);
DISPLAY 0.617021 (-4750 5525);
PAINT SKYBLUE (-4750 5525);
FORCEPROP 1 LAST VOLTAGE 16V
J 0
(-4750 5475);
DISPLAY 0.617021 (-4750 5475);
PAINT SKYBLUE (-4750 5475);
FORCEPROP 1 LAST PACK_TYPE C0402
J 0
(-4750 5325);
DISPLAY 0.617021 (-4750 5325);
PAINT SKYBLUE (-4750 5325);
FORCEPROP 1 LAST LOCATION PC486_P1_7
J 0
(-4750 5575);
DISPLAY 0.617021 (-4750 5575);
PAINT AQUA (-4750 5575);
FORCEPROP 1 LASTPIN (-4800 5525) $PN 1
J 0
(-4790 5505);
DISPLAY 0.617021 (-4790 5505);
PAINT MONO (-4790 5505);
FORCEPROP 1 LASTPIN (-4800 5325) $PN 2
J 0
(-4790 5305);
DISPLAY 0.617021 (-4790 5305);
PAINT MONO (-4790 5305);
FORCEPROP 2 LAST CDS_LIB pure_quanta
J 0
(-4800 5425);
DISPLAY INVISIBLE (-4800 5425);
FORCEPROP 1 LAST PATH I40
J 0
(-4750 5575);
DISPLAY 0.978723 (-4750 5575);
PAINT WHITE (-4750 5575);
DISPLAY INVISIBLE (-4750 5575);
FORCEPROP 1 LAST LOCATION PC486_P1_7
J 0
(-4750 5625);
DISPLAY 1.021277 (-4750 5625);
PAINT AQUA (-4750 5625);
DISPLAY INVISIBLE (-4750 5625);
FORCEPROP 0 LAST $SEC 1
J 0
(-4750 5625);
DISPLAY 0.680851 (-4750 5625);
PAINT MONO (-4750 5625);
DISPLAY INVISIBLE (-4750 5625);
FORCEPROP 0 LAST CDS_SEC 1
J 0
(-4750 5625);
DISPLAY 1.021277 (-4750 5625);
DISPLAY INVISIBLE (-4750 5625);
FORCEADD Q_CAP..1
(-4400 5425);
FORCEPROP 1 LAST PART_NUMBER CH6223MEA01
J 0
(-4350 5275);
DISPLAY 0.617021 (-4350 5275);
PAINT BLUE (-4350 5275);
DISPLAY INVISIBLE (-4350 5275);
FORCEPROP 1 LAST MATERIAL X6S
J 0
(-4350 5375);
DISPLAY 0.617021 (-4350 5375);
PAINT SKYBLUE (-4350 5375);
FORCEPROP 1 LAST TOLERANCE 20%
J 0
(-4350 5425);
DISPLAY 0.617021 (-4350 5425);
PAINT SKYBLUE (-4350 5425);
FORCEPROP 1 LAST VALUE 22UF
J 0
(-4350 5525);
DISPLAY 0.617021 (-4350 5525);
PAINT SKYBLUE (-4350 5525);
FORCEPROP 1 LAST VOLTAGE 16V
J 0
(-4350 5475);
DISPLAY 0.617021 (-4350 5475);
PAINT SKYBLUE (-4350 5475);
FORCEPROP 1 LAST PACK_TYPE C0805
J 0
(-4350 5325);
DISPLAY 0.617021 (-4350 5325);
PAINT SKYBLUE (-4350 5325);
FORCEPROP 1 LAST LOCATION PC490_P1_7
J 0
(-4350 5575);
DISPLAY 0.617021 (-4350 5575);
PAINT AQUA (-4350 5575);
FORCEPROP 1 LASTPIN (-4400 5525) $PN 1
J 0
(-4390 5505);
DISPLAY 0.617021 (-4390 5505);
PAINT MONO (-4390 5505);
FORCEPROP 1 LASTPIN (-4400 5325) $PN 2
J 0
(-4390 5305);
DISPLAY 0.617021 (-4390 5305);
PAINT MONO (-4390 5305);
FORCEPROP 2 LAST CDS_LIB pure_quanta
J 0
(-4400 5425);
DISPLAY INVISIBLE (-4400 5425);
FORCEPROP 1 LAST PATH I41
J 0
(-4350 5575);
DISPLAY 0.978723 (-4350 5575);
PAINT WHITE (-4350 5575);
DISPLAY INVISIBLE (-4350 5575);
FORCEPROP 1 LAST LOCATION PC490_P1_7
J 0
(-4350 5625);
DISPLAY 1.021277 (-4350 5625);
PAINT AQUA (-4350 5625);
DISPLAY INVISIBLE (-4350 5625);
FORCEPROP 0 LAST $SEC 1
J 0
(-4350 5625);
DISPLAY 0.680851 (-4350 5625);
PAINT MONO (-4350 5625);
DISPLAY INVISIBLE (-4350 5625);
FORCEPROP 0 LAST CDS_SEC 1
J 0
(-4350 5625);
DISPLAY 1.021277 (-4350 5625);
DISPLAY INVISIBLE (-4350 5625);
FORCEADD Q_CAP..1
R 2
(-4050 1975);
FORCEPROP 1 LAST PART_NUMBER CH4106K1B01
J 2
(-4100 1925);
DISPLAY 0.617021 (-4100 1925);
PAINT BLUE (-4100 1925);
DISPLAY INVISIBLE (-4100 1925);
FORCEPROP 1 LAST MATERIAL X7R
J 2
(-4100 1950);
DISPLAY 0.617021 (-4100 1950);
PAINT SKYBLUE (-4100 1950);
FORCEPROP 1 LAST TOLERANCE 10%
J 2
(-4100 1975);
DISPLAY 0.617021 (-4100 1975);
PAINT SKYBLUE (-4100 1975);
FORCEPROP 1 LAST VALUE 100NF
J 2
(-4100 2025);
DISPLAY 0.617021 (-4100 2025);
PAINT SKYBLUE (-4100 2025);
FORCEPROP 1 LAST VOLTAGE 50V
J 2
(-4100 2000);
DISPLAY 0.617021 (-4100 2000);
PAINT SKYBLUE (-4100 2000);
FORCEPROP 1 LAST PACK_TYPE C0402
J 2
(-4100 1900);
DISPLAY 0.617021 (-4100 1900);
PAINT SKYBLUE (-4100 1900);
FORCEPROP 1 LAST LOCATION PC487
J 2
(-4100 2050);
DISPLAY 0.617021 (-4100 2050);
PAINT AQUA (-4100 2050);
FORCEPROP 1 LASTPIN (-4050 2075) $PN 1
J 2
(-4060 2055);
DISPLAY 0.617021 (-4060 2055);
FORCEPROP 1 LASTPIN (-4050 1875) $PN 2
J 2
(-4060 1855);
DISPLAY 0.617021 (-4060 1855);
FORCEPROP 2 LAST CDS_LIB pure_quanta
J 2
(-4050 1975);
PAINT MONO (-4050 1975);
DISPLAY INVISIBLE (-4050 1975);
FORCEPROP 1 LAST PATH I42
J 2
(-4100 2125);
DISPLAY 0.978723 (-4100 2125);
PAINT WHITE (-4100 2125);
DISPLAY INVISIBLE (-4100 2125);
FORCEPROP 2 LAST $SEC 1
J 0
(-4100 2175);
DISPLAY 0.680851 (-4100 2175);
PAINT MONO (-4100 2175);
DISPLAY INVISIBLE (-4100 2175);
FORCEPROP 2 LAST CDS_SEC 1
J 0
(-4100 2175);
DISPLAY 1.021277 (-4100 2175);
DISPLAY INVISIBLE (-4100 2175);
FORCEADD Q_INDUCTOR4P_14..1
(-3500 1575);
FORCEPROP 1 LAST PART_NUMBER CV+15^0TZ04
J 0
(-3725 1735);
DISPLAY 0.617021 (-3725 1735);
PAINT BLUE (-3725 1735);
DISPLAY INVISIBLE (-3725 1735);
FORCEPROP 2 LAST VALUE 150NH
J 0
(-3725 1875);
DISPLAY 0.617021 (-3725 1875);
PAINT SKYBLUE (-3725 1875);
FORCEPROP 1 LAST MATERIAL IND
J 0
(-3725 1785);
DISPLAY 0.617021 (-3725 1785);
PAINT SKYBLUE (-3725 1785);
FORCEPROP 2 LAST PART_TYPE SMLF
J 0
(-3725 1925);
DISPLAY 1.021277 (-3725 1925);
FORCEPROP 1 LAST LOCATION PL24
J 0
(-3725 1830);
DISPLAY 0.617021 (-3725 1830);
PAINT AQUA (-3725 1830);
FORCEPROP 2 LASTPIN (-3900 1700) $PN 1
J 2
(-3910 1710);
DISPLAY 0.617021 (-3910 1710);
PAINT MONO (-3910 1710);
FORCEPROP 2 LASTPIN (-3900 1450) $PN 2
J 2
(-3910 1460);
DISPLAY 0.617021 (-3910 1460);
PAINT MONO (-3910 1460);
FORCEPROP 2 LASTPIN (-3100 1450) $PN 3
J 0
(-3090 1460);
DISPLAY 0.617021 (-3090 1460);
PAINT MONO (-3090 1460);
FORCEPROP 2 LASTPIN (-3100 1700) $PN 4
J 0
(-3090 1710);
DISPLAY 0.617021 (-3090 1710);
PAINT MONO (-3090 1710);
FORCEPROP 1 LAST NEEDS_NO_SIZE TRUE
J 0
(-3500 1575);
DISPLAY 0.468085 (-3500 1575);
PAINT GREEN (-3500 1575);
DISPLAY INVISIBLE (-3500 1575);
FORCEPROP 2 LAST CDS_LIB pure_quanta
J 0
(-3500 1575);
DISPLAY INVISIBLE (-3500 1575);
FORCEPROP 2 LAST SEC_TYPE 
J 0
(-3725 1975);
DISPLAY 1.021277 (-3725 1975);
DISPLAY INVISIBLE (-3725 1975);
FORCEPROP 1 LAST PATH I43
J 0
(-3300 1730);
DISPLAY 0.723404 (-3300 1730);
PAINT GREEN (-3300 1730);
DISPLAY INVISIBLE (-3300 1730);
FORCEPROP 2 LAST SEC 1
J 0
(-3725 1975);
DISPLAY 0.680851 (-3725 1975);
PAINT MONO (-3725 1975);
DISPLAY INVISIBLE (-3725 1975);
FORCEADD Q_RES..1
(-3525 1125);
FORCEPROP 1 LAST PART_NUMBER CS00002JB13
J 0
(-3650 1175);
DISPLAY 0.617021 (-3650 1175);
PAINT BLUE (-3650 1175);
DISPLAY INVISIBLE (-3650 1175);
FORCEPROP 1 LAST MATERIAL CHIP
J 0
(-3250 1125);
DISPLAY 0.617021 (-3250 1125);
PAINT SKYBLUE (-3250 1125);
FORCEPROP 1 LAST TOLERANCE 5%
J 0
(-3325 1125);
DISPLAY 0.617021 (-3325 1125);
PAINT SKYBLUE (-3325 1125);
FORCEPROP 1 LAST VALUE 0
J 2
(-3350 1125);
DISPLAY 0.617021 (-3350 1125);
PAINT SKYBLUE (-3350 1125);
FORCEPROP 1 LAST WATTAGE 1/16W
J 2
(-3275 1225);
DISPLAY 0.617021 (-3275 1225);
PAINT SKYBLUE (-3275 1225);
FORCEPROP 1 LAST PACK_TYPE 0402LF
J 0
(-3650 1225);
DISPLAY 0.617021 (-3650 1225);
PAINT SKYBLUE (-3650 1225);
FORCEPROP 1 LAST LOCATION PR289
J 0
(-3800 1125);
DISPLAY 0.617021 (-3800 1125);
PAINT AQUA (-3800 1125);
FORCEPROP 1 LASTPIN (-3625 1125) $PN 1
J 0
(-3613 1137);
DISPLAY 0.617021 (-3613 1137);
PAINT MONO (-3613 1137);
FORCEPROP 1 LASTPIN (-3425 1125) $PN 2
J 0
(-3463 1137);
DISPLAY 0.617021 (-3463 1137);
PAINT MONO (-3463 1137);
FORCEPROP 2 LAST CDS_LIB pure_quanta
J 0
(-3525 1125);
DISPLAY INVISIBLE (-3525 1125);
FORCEPROP 1 LAST PATH I44
J 0
(-3575 1275);
DISPLAY 0.978723 (-3575 1275);
PAINT WHITE (-3575 1275);
DISPLAY INVISIBLE (-3575 1275);
FORCEPROP 0 LAST $SEC 1
J 0
(-3275 1275);
DISPLAY 0.680851 (-3275 1275);
PAINT MONO (-3275 1275);
DISPLAY INVISIBLE (-3275 1275);
FORCEPROP 0 LAST CDS_SEC 1
J 0
(-3275 1275);
DISPLAY 1.021277 (-3275 1275);
DISPLAY INVISIBLE (-3275 1275);
FORCEADD OFFPAGE..3
(-2575 1450);
FORCEPROP 2 LAST $XR0 287 
J 0
(-2361 1450);
DISPLAY 0.638298 (-2361 1450);
PAINT MONO (-2361 1450);
FORCEPROP 1 LAST COMMENT_BODY TRUE
J 0
(-2625 1350);
DISPLAY 0.872340 (-2625 1350);
PAINT GREEN (-2625 1350);
DISPLAY INVISIBLE (-2625 1350);
FORCEPROP 1 LAST OFFPAGE TRUE
J 0
(-2250 1325);
DISPLAY 0.872340 (-2250 1325);
PAINT GREEN (-2250 1325);
DISPLAY INVISIBLE (-2250 1325);
FORCEPROP 2 LAST CDS_LIB standard
J 0
(-2575 1450);
DISPLAY INVISIBLE (-2575 1450);
FORCEPROP 2 LAST PATH I45
J 0
(-2350 1500);
DISPLAY 1.021277 (-2350 1500);
DISPLAY INVISIBLE (-2350 1500);
FORCEADD Q_CAP..1
(-4025 2600);
FORCEPROP 1 LAST PART_NUMBER CH6223MEA01
J 0
(-3975 2450);
DISPLAY 0.617021 (-3975 2450);
PAINT BLUE (-3975 2450);
DISPLAY INVISIBLE (-3975 2450);
FORCEPROP 1 LAST TOLERANCE 20%
J 0
(-3975 2600);
DISPLAY 0.617021 (-3975 2600);
PAINT SKYBLUE (-3975 2600);
FORCEPROP 1 LAST VOLTAGE 16V
J 0
(-3975 2650);
DISPLAY 0.617021 (-3975 2650);
PAINT SKYBLUE (-3975 2650);
FORCEPROP 1 LAST PACK_TYPE C0805
J 0
(-3975 2500);
DISPLAY 0.617021 (-3975 2500);
PAINT SKYBLUE (-3975 2500);
FORCEPROP 1 LAST VALUE 22UF
J 0
(-3975 2700);
DISPLAY 0.617021 (-3975 2700);
PAINT SKYBLUE (-3975 2700);
FORCEPROP 1 LAST MATERIAL X6S
J 0
(-3975 2550);
DISPLAY 0.617021 (-3975 2550);
PAINT SKYBLUE (-3975 2550);
FORCEPROP 1 LAST LOCATION PC491_P1_8
J 0
(-3975 2750);
DISPLAY 0.617021 (-3975 2750);
PAINT AQUA (-3975 2750);
FORCEPROP 1 LASTPIN (-4025 2700) $PN 1
J 0
(-4015 2680);
DISPLAY 0.617021 (-4015 2680);
PAINT MONO (-4015 2680);
FORCEPROP 1 LASTPIN (-4025 2500) $PN 2
J 0
(-4015 2480);
DISPLAY 0.617021 (-4015 2480);
PAINT MONO (-4015 2480);
FORCEPROP 2 LAST CDS_LIB pure_quanta
J 0
(-4025 2600);
DISPLAY INVISIBLE (-4025 2600);
FORCEPROP 1 LAST PATH I46
J 0
(-3975 2750);
DISPLAY 0.978723 (-3975 2750);
PAINT WHITE (-3975 2750);
DISPLAY INVISIBLE (-3975 2750);
FORCEPROP 1 LAST LOCATION PC491_P1_8
J 0
(-3975 2800);
DISPLAY 1.021277 (-3975 2800);
PAINT AQUA (-3975 2800);
DISPLAY INVISIBLE (-3975 2800);
FORCEPROP 0 LAST $SEC 1
J 0
(-3975 2800);
DISPLAY 0.680851 (-3975 2800);
PAINT MONO (-3975 2800);
DISPLAY INVISIBLE (-3975 2800);
FORCEPROP 0 LAST CDS_SEC 1
J 0
(-3975 2800);
DISPLAY 1.021277 (-3975 2800);
DISPLAY INVISIBLE (-3975 2800);
FORCEADD Q_CAP..1
(-3650 2600);
FORCEPROP 1 LAST PART_NUMBER CH6223MEA01
J 0
(-3600 2450);
DISPLAY 0.617021 (-3600 2450);
PAINT BLUE (-3600 2450);
DISPLAY INVISIBLE (-3600 2450);
FORCEPROP 1 LAST MATERIAL X6S
J 0
(-3600 2550);
DISPLAY 0.617021 (-3600 2550);
PAINT SKYBLUE (-3600 2550);
FORCEPROP 1 LAST TOLERANCE 20%
J 0
(-3600 2600);
DISPLAY 0.617021 (-3600 2600);
PAINT SKYBLUE (-3600 2600);
FORCEPROP 1 LAST VALUE 22UF
J 0
(-3600 2700);
DISPLAY 0.617021 (-3600 2700);
PAINT SKYBLUE (-3600 2700);
FORCEPROP 1 LAST VOLTAGE 16V
J 0
(-3600 2650);
DISPLAY 0.617021 (-3600 2650);
PAINT SKYBLUE (-3600 2650);
FORCEPROP 1 LAST PACK_TYPE C0805
J 0
(-3600 2500);
DISPLAY 0.617021 (-3600 2500);
PAINT SKYBLUE (-3600 2500);
FORCEPROP 1 LAST LOCATION PC493_P1_8
J 0
(-3600 2750);
DISPLAY 0.617021 (-3600 2750);
PAINT AQUA (-3600 2750);
FORCEPROP 1 LASTPIN (-3650 2700) $PN 1
J 0
(-3640 2680);
DISPLAY 0.617021 (-3640 2680);
PAINT MONO (-3640 2680);
FORCEPROP 1 LASTPIN (-3650 2500) $PN 2
J 0
(-3640 2480);
DISPLAY 0.617021 (-3640 2480);
PAINT MONO (-3640 2480);
FORCEPROP 2 LAST CDS_LIB pure_quanta
J 0
(-3650 2600);
DISPLAY INVISIBLE (-3650 2600);
FORCEPROP 1 LAST PATH I47
J 0
(-3600 2750);
DISPLAY 0.978723 (-3600 2750);
PAINT WHITE (-3600 2750);
DISPLAY INVISIBLE (-3600 2750);
FORCEPROP 1 LAST LOCATION PC493_P1_8
J 0
(-3600 2800);
DISPLAY 1.021277 (-3600 2800);
PAINT AQUA (-3600 2800);
DISPLAY INVISIBLE (-3600 2800);
FORCEPROP 0 LAST $SEC 1
J 0
(-3600 2800);
DISPLAY 0.680851 (-3600 2800);
PAINT MONO (-3600 2800);
DISPLAY INVISIBLE (-3600 2800);
FORCEPROP 0 LAST CDS_SEC 1
J 0
(-3600 2800);
DISPLAY 1.021277 (-3600 2800);
DISPLAY INVISIBLE (-3600 2800);
FORCEADD UNIVERSAL_GND..1
(-3425 2175);
FORCEPROP 3 LASTPIN (-3425 2225) SIG_NAME GND\g
J 0
(-3415 2235);
DISPLAY 0.659574 (-3415 2235);
PAINT MONO (-3415 2235);
DISPLAY INVISIBLE (-3415 2235);
FORCEPROP 2 LAST CDS_LIB logical_power
J 0
(-3425 2175);
PAINT MONO (-3425 2175);
DISPLAY INVISIBLE (-3425 2175);
FORCEPROP 1 LAST HDL_POWER GND
J 1
(-3400 2100);
DISPLAY 0.872340 (-3400 2100);
PAINT GREEN (-3400 2100);
DISPLAY INVISIBLE (-3400 2100);
FORCEPROP 1 LAST PATH I48
J 0
(-3350 2175);
DISPLAY 0.872340 (-3350 2175);
PAINT AQUA (-3350 2175);
DISPLAY INVISIBLE (-3350 2175);
FORCEADD VCC15..1
(-3425 2975);
FORCEPROP 3 LASTPIN (-3425 2925) SIG_NAME SW_P12V_PVCCIN_CPU1_FLT\g
J 0
(-3415 2935);
DISPLAY 0.659574 (-3415 2935);
PAINT MONO (-3415 2935);
DISPLAY INVISIBLE (-3415 2935);
FORCEPROP 1 LAST HDL_POWER SW_P12V_PVCCIN_CPU1_FLT
J 1
(-3375 3025);
DISPLAY 0.617021 (-3375 3025);
PAINT GREEN (-3375 3025);
FORCEPROP 2 LAST CDS_LIB logical_power
J 0
(-3425 2975);
DISPLAY INVISIBLE (-3425 2975);
FORCEPROP 1 LAST PATH I49
J 0
(-3375 3000);
DISPLAY 0.872340 (-3375 3000);
PAINT AQUA (-3375 3000);
DISPLAY INVISIBLE (-3375 3000);
FORCEADD OFFPAGE..5
(-7475 1200);
FORCEPROP 2 LAST $XR4 284 
J 0
(-7760 1272);
DISPLAY 0.638298 (-7760 1272);
PAINT MONO (-7760 1272);
FORCEPROP 2 LAST $XR3 288 
J 0
(-7760 1128);
DISPLAY 0.638298 (-7760 1128);
PAINT MONO (-7760 1128);
FORCEPROP 2 LAST $XR2 287 
J 0
(-7760 1236);
DISPLAY 0.638298 (-7760 1236);
PAINT MONO (-7760 1236);
FORCEPROP 2 LAST $XR1 286 
J 0
(-7760 1164);
DISPLAY 0.638298 (-7760 1164);
PAINT MONO (-7760 1164);
FORCEPROP 2 LAST $XR0 285 
J 0
(-7760 1200);
DISPLAY 0.638298 (-7760 1200);
PAINT MONO (-7760 1200);
FORCEPROP 1 LAST COMMENT_BODY TRUE
J 0
(-7375 1125);
DISPLAY 0.872340 (-7375 1125);
PAINT GREEN (-7375 1125);
DISPLAY INVISIBLE (-7375 1125);
FORCEPROP 1 LAST OFFPAGE TRUE
J 0
(-7150 1075);
DISPLAY 0.872340 (-7150 1075);
PAINT GREEN (-7150 1075);
DISPLAY INVISIBLE (-7150 1075);
FORCEPROP 2 LAST CDS_LIB standard
J 0
(-7475 1200);
DISPLAY INVISIBLE (-7475 1200);
FORCEPROP 2 LAST PATH I5
J 0
(-7750 1325);
DISPLAY 1.021277 (-7750 1325);
DISPLAY INVISIBLE (-7750 1325);
FORCEADD Q_RES..1
(-3525 3950);
FORCEPROP 1 LAST PART_NUMBER CS00002JB13
J 0
(-3650 4000);
DISPLAY 0.617021 (-3650 4000);
PAINT BLUE (-3650 4000);
DISPLAY INVISIBLE (-3650 4000);
FORCEPROP 1 LAST PACK_TYPE 0402LF
J 0
(-3650 4050);
DISPLAY 0.617021 (-3650 4050);
PAINT SKYBLUE (-3650 4050);
FORCEPROP 1 LAST VALUE 0
J 2
(-3350 3950);
DISPLAY 0.617021 (-3350 3950);
PAINT SKYBLUE (-3350 3950);
FORCEPROP 1 LAST MATERIAL CHIP
J 0
(-3250 3950);
DISPLAY 0.617021 (-3250 3950);
PAINT SKYBLUE (-3250 3950);
FORCEPROP 1 LAST TOLERANCE 5%
J 0
(-3325 3950);
DISPLAY 0.617021 (-3325 3950);
PAINT SKYBLUE (-3325 3950);
FORCEPROP 1 LAST WATTAGE 1/16W
J 2
(-3275 4050);
DISPLAY 0.617021 (-3275 4050);
PAINT SKYBLUE (-3275 4050);
FORCEPROP 1 LAST LOCATION PR290
J 0
(-3800 3950);
DISPLAY 0.617021 (-3800 3950);
PAINT AQUA (-3800 3950);
FORCEPROP 1 LASTPIN (-3625 3950) $PN 1
J 0
(-3613 3962);
DISPLAY 0.617021 (-3613 3962);
PAINT MONO (-3613 3962);
FORCEPROP 1 LASTPIN (-3425 3950) $PN 2
J 0
(-3463 3962);
DISPLAY 0.617021 (-3463 3962);
PAINT MONO (-3463 3962);
FORCEPROP 2 LAST CDS_LIB pure_quanta
J 0
(-3525 3950);
DISPLAY INVISIBLE (-3525 3950);
FORCEPROP 1 LAST PATH I50
J 0
(-3575 4100);
DISPLAY 0.978723 (-3575 4100);
PAINT WHITE (-3575 4100);
DISPLAY INVISIBLE (-3575 4100);
FORCEPROP 0 LAST $SEC 1
J 0
(-3275 4100);
DISPLAY 0.680851 (-3275 4100);
PAINT MONO (-3275 4100);
DISPLAY INVISIBLE (-3275 4100);
FORCEPROP 0 LAST CDS_SEC 1
J 0
(-3275 4100);
DISPLAY 1.021277 (-3275 4100);
DISPLAY INVISIBLE (-3275 4100);
FORCEADD UNIVERSAL_GND..1
(-2975 4150);
FORCEPROP 3 LASTPIN (-2975 4200) SIG_NAME GND\g
J 0
(-2965 4210);
DISPLAY 0.659574 (-2965 4210);
PAINT MONO (-2965 4210);
DISPLAY INVISIBLE (-2965 4210);
FORCEPROP 2 LAST CDS_LIB logical_power
J 0
(-2975 4150);
DISPLAY INVISIBLE (-2975 4150);
FORCEPROP 1 LAST HDL_POWER GND
J 1
(-2950 4075);
DISPLAY 0.872340 (-2950 4075);
PAINT GREEN (-2950 4075);
DISPLAY INVISIBLE (-2950 4075);
FORCEPROP 1 LAST PATH I51
J 0
(-2900 4150);
DISPLAY 0.872340 (-2900 4150);
PAINT AQUA (-2900 4150);
DISPLAY INVISIBLE (-2900 4150);
FORCEADD Q_CAP..1
(-1925 1500);
FORCEPROP 1 LAST PART_NUMBER CH5103KEB01
J 0
(-1875 1325);
DISPLAY 0.617021 (-1875 1325);
PAINT BLUE (-1875 1325);
DISPLAY INVISIBLE (-1875 1325);
FORCEPROP 1 LAST TOLERANCE 10%
J 0
(-1875 1475);
DISPLAY 0.617021 (-1875 1475);
PAINT SKYBLUE (-1875 1475);
FORCEPROP 1 LAST VALUE 1UF
J 0
(-1875 1575);
DISPLAY 0.617021 (-1875 1575);
PAINT SKYBLUE (-1875 1575);
FORCEPROP 1 LAST VOLTAGE 16V
J 0
(-1875 1525);
DISPLAY 0.617021 (-1875 1525);
PAINT SKYBLUE (-1875 1525);
FORCEPROP 1 LAST MATERIAL X6S
J 0
(-1875 1425);
DISPLAY 0.617021 (-1875 1425);
PAINT SKYBLUE (-1875 1425);
FORCEPROP 1 LAST PACK_TYPE C0402
J 0
(-1875 1375);
DISPLAY 0.617021 (-1875 1375);
PAINT SKYBLUE (-1875 1375);
FORCEPROP 1 LAST LOCATION PC495_P1_8
J 0
(-1875 1625);
DISPLAY 0.617021 (-1875 1625);
PAINT AQUA (-1875 1625);
FORCEPROP 1 LASTPIN (-1925 1600) $PN 1
J 0
(-1915 1580);
DISPLAY 0.617021 (-1915 1580);
PAINT MONO (-1915 1580);
FORCEPROP 1 LASTPIN (-1925 1400) $PN 2
J 0
(-1915 1380);
DISPLAY 0.617021 (-1915 1380);
PAINT MONO (-1915 1380);
FORCEPROP 2 LAST CDS_LIB pure_quanta
J 0
(-1925 1500);
DISPLAY INVISIBLE (-1925 1500);
FORCEPROP 1 LAST PATH I52
J 0
(-1875 1650);
DISPLAY 0.978723 (-1875 1650);
PAINT WHITE (-1875 1650);
DISPLAY INVISIBLE (-1875 1650);
FORCEPROP 1 LAST LOCATION PC495_P1_8
J 0
(-1875 1675);
DISPLAY 1.021277 (-1875 1675);
PAINT AQUA (-1875 1675);
DISPLAY INVISIBLE (-1875 1675);
FORCEPROP 0 LAST $SEC 1
J 0
(-1875 1675);
DISPLAY 0.680851 (-1875 1675);
PAINT MONO (-1875 1675);
DISPLAY INVISIBLE (-1875 1675);
FORCEPROP 0 LAST CDS_SEC 1
J 0
(-1875 1675);
DISPLAY 1.021277 (-1875 1675);
DISPLAY INVISIBLE (-1875 1675);
FORCEADD Q_CAP..1
(-1500 1500);
FORCEPROP 1 LAST PART_NUMBER CH622KMEA03
J 0
(-1450 1325);
DISPLAY 0.617021 (-1450 1325);
PAINT BLUE (-1450 1325);
DISPLAY INVISIBLE (-1450 1325);
FORCEPROP 1 LAST PACK_TYPE C0805
J 0
(-1450 1375);
DISPLAY 0.617021 (-1450 1375);
PAINT SKYBLUE (-1450 1375);
FORCEPROP 1 LAST VOLTAGE 4V
J 0
(-1450 1525);
DISPLAY 0.617021 (-1450 1525);
PAINT SKYBLUE (-1450 1525);
FORCEPROP 1 LAST VALUE 22UF
J 0
(-1450 1575);
DISPLAY 0.617021 (-1450 1575);
PAINT SKYBLUE (-1450 1575);
FORCEPROP 1 LAST TOLERANCE 20%
J 0
(-1450 1475);
DISPLAY 0.617021 (-1450 1475);
PAINT SKYBLUE (-1450 1475);
FORCEPROP 1 LAST MATERIAL X6S
J 0
(-1450 1425);
DISPLAY 0.617021 (-1450 1425);
PAINT SKYBLUE (-1450 1425);
FORCEPROP 1 LAST LOCATION PC497_P1_8
J 0
(-1450 1625);
DISPLAY 0.617021 (-1450 1625);
PAINT AQUA (-1450 1625);
FORCEPROP 1 LASTPIN (-1500 1600) $PN 1
J 0
(-1490 1580);
DISPLAY 0.617021 (-1490 1580);
PAINT MONO (-1490 1580);
FORCEPROP 1 LASTPIN (-1500 1400) $PN 2
J 0
(-1490 1380);
DISPLAY 0.617021 (-1490 1380);
PAINT MONO (-1490 1380);
FORCEPROP 2 LAST CDS_LIB pure_quanta
J 0
(-1500 1500);
DISPLAY INVISIBLE (-1500 1500);
FORCEPROP 1 LAST PATH I53
J 0
(-1450 1650);
DISPLAY 0.978723 (-1450 1650);
PAINT WHITE (-1450 1650);
DISPLAY INVISIBLE (-1450 1650);
FORCEPROP 1 LAST LOCATION PC497_P1_8
J 0
(-1450 1675);
DISPLAY 1.021277 (-1450 1675);
PAINT AQUA (-1450 1675);
DISPLAY INVISIBLE (-1450 1675);
FORCEPROP 0 LAST $SEC 1
J 0
(-1450 1675);
DISPLAY 0.680851 (-1450 1675);
PAINT MONO (-1450 1675);
DISPLAY INVISIBLE (-1450 1675);
FORCEPROP 0 LAST CDS_SEC 1
J 0
(-1450 1675);
DISPLAY 1.021277 (-1450 1675);
DISPLAY INVISIBLE (-1450 1675);
FORCEADD Q_CAP..1
(-1075 1500);
FORCEPROP 1 LAST PART_NUMBER CH622KMEA03
J 0
(-1025 1325);
DISPLAY 0.617021 (-1025 1325);
PAINT BLUE (-1025 1325);
DISPLAY INVISIBLE (-1025 1325);
FORCEPROP 1 LAST PACK_TYPE C0805
J 0
(-1025 1375);
DISPLAY 0.617021 (-1025 1375);
PAINT SKYBLUE (-1025 1375);
FORCEPROP 1 LAST VOLTAGE 4V
J 0
(-1025 1525);
DISPLAY 0.617021 (-1025 1525);
PAINT SKYBLUE (-1025 1525);
FORCEPROP 1 LAST VALUE 22UF
J 0
(-1025 1575);
DISPLAY 0.617021 (-1025 1575);
PAINT SKYBLUE (-1025 1575);
FORCEPROP 1 LAST TOLERANCE 20%
J 0
(-1025 1475);
DISPLAY 0.617021 (-1025 1475);
PAINT SKYBLUE (-1025 1475);
FORCEPROP 1 LAST MATERIAL X6S
J 0
(-1025 1425);
DISPLAY 0.617021 (-1025 1425);
PAINT SKYBLUE (-1025 1425);
FORCEPROP 1 LAST LOCATION PC499_P1_8
J 0
(-1025 1625);
DISPLAY 0.617021 (-1025 1625);
PAINT AQUA (-1025 1625);
FORCEPROP 1 LASTPIN (-1075 1600) $PN 1
J 0
(-1065 1580);
DISPLAY 0.617021 (-1065 1580);
PAINT MONO (-1065 1580);
FORCEPROP 1 LASTPIN (-1075 1400) $PN 2
J 0
(-1065 1380);
DISPLAY 0.617021 (-1065 1380);
PAINT MONO (-1065 1380);
FORCEPROP 2 LAST CDS_LIB pure_quanta
J 0
(-1075 1500);
DISPLAY INVISIBLE (-1075 1500);
FORCEPROP 1 LAST PATH I54
J 0
(-1025 1650);
DISPLAY 0.978723 (-1025 1650);
PAINT WHITE (-1025 1650);
DISPLAY INVISIBLE (-1025 1650);
FORCEPROP 1 LAST LOCATION PC499_P1_8
J 0
(-1025 1675);
DISPLAY 1.021277 (-1025 1675);
PAINT AQUA (-1025 1675);
DISPLAY INVISIBLE (-1025 1675);
FORCEPROP 0 LAST $SEC 1
J 0
(-1025 1675);
DISPLAY 0.680851 (-1025 1675);
PAINT MONO (-1025 1675);
DISPLAY INVISIBLE (-1025 1675);
FORCEPROP 0 LAST CDS_SEC 1
J 0
(-1025 1675);
DISPLAY 1.021277 (-1025 1675);
DISPLAY INVISIBLE (-1025 1675);
FORCEADD UNIVERSAL_GND..1
(-775 1125);
FORCEPROP 3 LASTPIN (-775 1175) SIG_NAME GND\g
J 0
(-765 1185);
DISPLAY 0.659574 (-765 1185);
PAINT MONO (-765 1185);
DISPLAY INVISIBLE (-765 1185);
FORCEPROP 2 LAST CDS_LIB logical_power
J 0
(-775 1125);
PAINT MONO (-775 1125);
DISPLAY INVISIBLE (-775 1125);
FORCEPROP 1 LAST HDL_POWER GND
J 1
(-750 1050);
DISPLAY 0.872340 (-750 1050);
PAINT GREEN (-750 1050);
DISPLAY INVISIBLE (-750 1050);
FORCEPROP 1 LAST PATH I55
J 0
(-700 1125);
DISPLAY 0.872340 (-700 1125);
PAINT AQUA (-700 1125);
DISPLAY INVISIBLE (-700 1125);
FORCEADD VCC15..1
(-775 1900);
FORCEPROP 3 LASTPIN (-775 1850) SIG_NAME PVCCIN_CPU1\g
J 0
(-765 1860);
DISPLAY 0.659574 (-765 1860);
PAINT MONO (-765 1860);
DISPLAY INVISIBLE (-765 1860);
FORCEPROP 1 LAST HDL_POWER PVCCIN_CPU1
J 1
(-775 1950);
DISPLAY 0.617021 (-775 1950);
PAINT GREEN (-775 1950);
FORCEPROP 2 LAST CDS_LIB logical_power
J 0
(-775 1900);
DISPLAY INVISIBLE (-775 1900);
FORCEPROP 1 LAST PATH I56
J 0
(-725 1925);
DISPLAY 0.872340 (-725 1925);
PAINT AQUA (-725 1925);
DISPLAY INVISIBLE (-725 1925);
FORCEADD UNIVERSAL_GND..1
(-525 3950);
FORCEPROP 3 LASTPIN (-525 4000) SIG_NAME GND\g
J 0
(-515 4010);
DISPLAY 0.659574 (-515 4010);
PAINT MONO (-515 4010);
DISPLAY INVISIBLE (-515 4010);
FORCEPROP 2 LAST CDS_LIB logical_power
J 0
(-525 3950);
PAINT MONO (-525 3950);
DISPLAY INVISIBLE (-525 3950);
FORCEPROP 1 LAST HDL_POWER GND
J 1
(-500 3875);
DISPLAY 0.872340 (-500 3875);
PAINT GREEN (-500 3875);
DISPLAY INVISIBLE (-500 3875);
FORCEPROP 1 LAST PATH I57
J 0
(-450 3950);
DISPLAY 0.872340 (-450 3950);
PAINT AQUA (-450 3950);
DISPLAY INVISIBLE (-450 3950);
FORCEADD Q_INDUCTOR4P_14..1
(-3550 4400);
FORCEPROP 1 LAST PART_NUMBER CV+15^0TZ04
J 0
(-3775 4560);
DISPLAY 0.617021 (-3775 4560);
PAINT BLUE (-3775 4560);
DISPLAY INVISIBLE (-3775 4560);
FORCEPROP 1 LAST MATERIAL IND
J 0
(-3775 4610);
DISPLAY 0.617021 (-3775 4610);
PAINT SKYBLUE (-3775 4610);
FORCEPROP 2 LAST VALUE 150NH
J 0
(-3775 4700);
DISPLAY 0.617021 (-3775 4700);
PAINT SKYBLUE (-3775 4700);
FORCEPROP 2 LAST PART_TYPE SMLF
J 0
(-3775 4750);
DISPLAY 1.021277 (-3775 4750);
FORCEPROP 1 LAST LOCATION PL25
J 0
(-3775 4655);
DISPLAY 0.617021 (-3775 4655);
PAINT AQUA (-3775 4655);
FORCEPROP 2 LASTPIN (-3950 4525) $PN 1
J 2
(-3960 4535);
DISPLAY 0.617021 (-3960 4535);
PAINT MONO (-3960 4535);
FORCEPROP 2 LASTPIN (-3950 4275) $PN 2
J 2
(-3960 4285);
DISPLAY 0.617021 (-3960 4285);
PAINT MONO (-3960 4285);
FORCEPROP 2 LASTPIN (-3150 4275) $PN 3
J 0
(-3140 4285);
DISPLAY 0.617021 (-3140 4285);
PAINT MONO (-3140 4285);
FORCEPROP 2 LASTPIN (-3150 4525) $PN 4
J 0
(-3140 4535);
DISPLAY 0.617021 (-3140 4535);
PAINT MONO (-3140 4535);
FORCEPROP 1 LAST NEEDS_NO_SIZE TRUE
J 0
(-3550 4400);
DISPLAY 0.468085 (-3550 4400);
PAINT GREEN (-3550 4400);
DISPLAY INVISIBLE (-3550 4400);
FORCEPROP 2 LAST CDS_LIB pure_quanta
J 0
(-3550 4400);
DISPLAY INVISIBLE (-3550 4400);
FORCEPROP 2 LAST SEC_TYPE 
J 0
(-3775 4800);
DISPLAY 1.021277 (-3775 4800);
DISPLAY INVISIBLE (-3775 4800);
FORCEPROP 1 LAST PATH I58
J 0
(-3350 4555);
DISPLAY 0.723404 (-3350 4555);
PAINT GREEN (-3350 4555);
DISPLAY INVISIBLE (-3350 4555);
FORCEPROP 2 LAST SEC 1
J 0
(-3775 4800);
DISPLAY 0.680851 (-3775 4800);
PAINT MONO (-3775 4800);
DISPLAY INVISIBLE (-3775 4800);
FORCEADD Q_CAP..1
R 2
(-4025 4800);
FORCEPROP 1 LAST PART_NUMBER CH4106K1B01
J 2
(-4075 4750);
DISPLAY 0.617021 (-4075 4750);
PAINT BLUE (-4075 4750);
DISPLAY INVISIBLE (-4075 4750);
FORCEPROP 1 LAST MATERIAL X7R
J 2
(-4075 4775);
DISPLAY 0.617021 (-4075 4775);
PAINT SKYBLUE (-4075 4775);
FORCEPROP 1 LAST VALUE 100NF
J 2
(-4075 4850);
DISPLAY 0.617021 (-4075 4850);
PAINT SKYBLUE (-4075 4850);
FORCEPROP 1 LAST VOLTAGE 50V
J 2
(-4075 4825);
DISPLAY 0.617021 (-4075 4825);
PAINT SKYBLUE (-4075 4825);
FORCEPROP 1 LAST PACK_TYPE C0402
J 2
(-4075 4725);
DISPLAY 0.617021 (-4075 4725);
PAINT SKYBLUE (-4075 4725);
FORCEPROP 1 LAST TOLERANCE 10%
J 2
(-4075 4800);
DISPLAY 0.617021 (-4075 4800);
PAINT SKYBLUE (-4075 4800);
FORCEPROP 1 LAST LOCATION PC488
J 2
(-4075 4875);
DISPLAY 0.617021 (-4075 4875);
PAINT AQUA (-4075 4875);
FORCEPROP 1 LASTPIN (-4025 4900) $PN 1
J 2
(-4035 4880);
DISPLAY 0.617021 (-4035 4880);
FORCEPROP 1 LASTPIN (-4025 4700) $PN 2
J 2
(-4035 4680);
DISPLAY 0.617021 (-4035 4680);
FORCEPROP 2 LAST CDS_LIB pure_quanta
J 2
(-4025 4800);
PAINT MONO (-4025 4800);
DISPLAY INVISIBLE (-4025 4800);
FORCEPROP 1 LAST PATH I59
J 2
(-4075 4950);
DISPLAY 0.978723 (-4075 4950);
PAINT WHITE (-4075 4950);
DISPLAY INVISIBLE (-4075 4950);
FORCEPROP 2 LAST $SEC 1
J 0
(-4075 5000);
DISPLAY 0.680851 (-4075 5000);
PAINT MONO (-4075 5000);
DISPLAY INVISIBLE (-4075 5000);
FORCEPROP 2 LAST CDS_SEC 1
J 0
(-4075 5000);
DISPLAY 1.021277 (-4075 5000);
DISPLAY INVISIBLE (-4075 5000);
FORCEADD OFFPAGE..1
(-7475 1600);
FORCEPROP 2 LAST $XR6 290 
J 0
(-8447 1600);
DISPLAY 0.638298 (-8447 1600);
PAINT MONO (-8447 1600);
FORCEPROP 2 LAST $XR5 289 
J 0
(-8327 1600);
DISPLAY 0.638298 (-8327 1600);
PAINT MONO (-8327 1600);
FORCEPROP 2 LAST $XR4 288 
J 0
(-8207 1600);
DISPLAY 0.638298 (-8207 1600);
PAINT MONO (-8207 1600);
FORCEPROP 2 LAST $XR3 287 
J 0
(-8087 1600);
DISPLAY 0.638298 (-8087 1600);
PAINT MONO (-8087 1600);
FORCEPROP 2 LAST $XR2 286 
J 0
(-7967 1600);
DISPLAY 0.638298 (-7967 1600);
PAINT MONO (-7967 1600);
FORCEPROP 2 LAST $XR1 285 
J 0
(-7847 1600);
DISPLAY 0.638298 (-7847 1600);
PAINT MONO (-7847 1600);
FORCEPROP 2 LAST $XR0 284 
J 0
(-7727 1600);
DISPLAY 0.638298 (-7727 1600);
PAINT MONO (-7727 1600);
FORCEPROP 1 LAST COMMENT_BODY TRUE
J 0
(-7350 1500);
DISPLAY 0.872340 (-7350 1500);
PAINT GREEN (-7350 1500);
DISPLAY INVISIBLE (-7350 1500);
FORCEPROP 1 LAST OFFPAGE TRUE
J 0
(-7150 1475);
DISPLAY 0.872340 (-7150 1475);
PAINT GREEN (-7150 1475);
DISPLAY INVISIBLE (-7150 1475);
FORCEPROP 2 LAST CDS_LIB standard
J 0
(-7475 1600);
DISPLAY INVISIBLE (-7475 1600);
FORCEPROP 2 LAST PATH I6
J 0
(-7725 1650);
DISPLAY 1.021277 (-7725 1650);
DISPLAY INVISIBLE (-7725 1650);
FORCEADD UNIVERSAL_GND..1
(-3400 5000);
FORCEPROP 3 LASTPIN (-3400 5050) SIG_NAME GND\g
J 0
(-3390 5060);
DISPLAY 0.659574 (-3390 5060);
PAINT MONO (-3390 5060);
DISPLAY INVISIBLE (-3390 5060);
FORCEPROP 2 LAST CDS_LIB logical_power
J 0
(-3400 5000);
PAINT MONO (-3400 5000);
DISPLAY INVISIBLE (-3400 5000);
FORCEPROP 1 LAST HDL_POWER GND
J 1
(-3375 4925);
DISPLAY 0.872340 (-3375 4925);
PAINT GREEN (-3375 4925);
DISPLAY INVISIBLE (-3375 4925);
FORCEPROP 1 LAST PATH I60
J 0
(-3325 5000);
DISPLAY 0.872340 (-3325 5000);
PAINT AQUA (-3325 5000);
DISPLAY INVISIBLE (-3325 5000);
FORCEADD Q_CAP..1
(-4000 5425);
FORCEPROP 1 LAST PART_NUMBER CH6223MEA01
J 0
(-3950 5275);
DISPLAY 0.617021 (-3950 5275);
PAINT BLUE (-3950 5275);
DISPLAY INVISIBLE (-3950 5275);
FORCEPROP 1 LAST MATERIAL X6S
J 0
(-3950 5375);
DISPLAY 0.617021 (-3950 5375);
PAINT SKYBLUE (-3950 5375);
FORCEPROP 1 LAST TOLERANCE 20%
J 0
(-3950 5425);
DISPLAY 0.617021 (-3950 5425);
PAINT SKYBLUE (-3950 5425);
FORCEPROP 1 LAST VALUE 22UF
J 0
(-3950 5525);
DISPLAY 0.617021 (-3950 5525);
PAINT SKYBLUE (-3950 5525);
FORCEPROP 1 LAST VOLTAGE 16V
J 0
(-3950 5475);
DISPLAY 0.617021 (-3950 5475);
PAINT SKYBLUE (-3950 5475);
FORCEPROP 1 LAST PACK_TYPE C0805
J 0
(-3950 5325);
DISPLAY 0.617021 (-3950 5325);
PAINT SKYBLUE (-3950 5325);
FORCEPROP 1 LAST LOCATION PC492_P1_7
J 0
(-3950 5575);
DISPLAY 0.617021 (-3950 5575);
PAINT AQUA (-3950 5575);
FORCEPROP 1 LASTPIN (-4000 5525) $PN 1
J 0
(-3990 5505);
DISPLAY 0.617021 (-3990 5505);
PAINT MONO (-3990 5505);
FORCEPROP 1 LASTPIN (-4000 5325) $PN 2
J 0
(-3990 5305);
DISPLAY 0.617021 (-3990 5305);
PAINT MONO (-3990 5305);
FORCEPROP 2 LAST CDS_LIB pure_quanta
J 0
(-4000 5425);
DISPLAY INVISIBLE (-4000 5425);
FORCEPROP 1 LAST PATH I61
J 0
(-3950 5575);
DISPLAY 0.978723 (-3950 5575);
PAINT WHITE (-3950 5575);
DISPLAY INVISIBLE (-3950 5575);
FORCEPROP 1 LAST LOCATION PC492_P1_7
J 0
(-3950 5625);
DISPLAY 1.021277 (-3950 5625);
PAINT AQUA (-3950 5625);
DISPLAY INVISIBLE (-3950 5625);
FORCEPROP 0 LAST $SEC 1
J 0
(-3950 5625);
DISPLAY 0.680851 (-3950 5625);
PAINT MONO (-3950 5625);
DISPLAY INVISIBLE (-3950 5625);
FORCEPROP 0 LAST CDS_SEC 1
J 0
(-3950 5625);
DISPLAY 1.021277 (-3950 5625);
DISPLAY INVISIBLE (-3950 5625);
FORCEADD Q_CAP..1
(-3625 5425);
FORCEPROP 1 LAST PART_NUMBER CH6223MEA01
J 0
(-3575 5275);
DISPLAY 0.617021 (-3575 5275);
PAINT BLUE (-3575 5275);
DISPLAY INVISIBLE (-3575 5275);
FORCEPROP 1 LAST PACK_TYPE C0805
J 0
(-3575 5325);
DISPLAY 0.617021 (-3575 5325);
PAINT SKYBLUE (-3575 5325);
FORCEPROP 1 LAST MATERIAL X6S
J 0
(-3575 5375);
DISPLAY 0.617021 (-3575 5375);
PAINT SKYBLUE (-3575 5375);
FORCEPROP 1 LAST TOLERANCE 20%
J 0
(-3575 5425);
DISPLAY 0.617021 (-3575 5425);
PAINT SKYBLUE (-3575 5425);
FORCEPROP 1 LAST VALUE 22UF
J 0
(-3575 5525);
DISPLAY 0.617021 (-3575 5525);
PAINT SKYBLUE (-3575 5525);
FORCEPROP 1 LAST VOLTAGE 16V
J 0
(-3575 5475);
DISPLAY 0.617021 (-3575 5475);
PAINT SKYBLUE (-3575 5475);
FORCEPROP 1 LAST LOCATION PC494_P1_7
J 0
(-3575 5575);
DISPLAY 0.617021 (-3575 5575);
PAINT AQUA (-3575 5575);
FORCEPROP 1 LASTPIN (-3625 5525) $PN 1
J 0
(-3615 5505);
DISPLAY 0.617021 (-3615 5505);
PAINT MONO (-3615 5505);
FORCEPROP 1 LASTPIN (-3625 5325) $PN 2
J 0
(-3615 5305);
DISPLAY 0.617021 (-3615 5305);
PAINT MONO (-3615 5305);
FORCEPROP 2 LAST CDS_LIB pure_quanta
J 0
(-3625 5425);
DISPLAY INVISIBLE (-3625 5425);
FORCEPROP 1 LAST PATH I62
J 0
(-3575 5575);
DISPLAY 0.978723 (-3575 5575);
PAINT WHITE (-3575 5575);
DISPLAY INVISIBLE (-3575 5575);
FORCEPROP 1 LAST LOCATION PC494_P1_7
J 0
(-3575 5625);
DISPLAY 1.021277 (-3575 5625);
PAINT AQUA (-3575 5625);
DISPLAY INVISIBLE (-3575 5625);
FORCEPROP 0 LAST $SEC 1
J 0
(-3575 5625);
DISPLAY 0.680851 (-3575 5625);
PAINT MONO (-3575 5625);
DISPLAY INVISIBLE (-3575 5625);
FORCEPROP 0 LAST CDS_SEC 1
J 0
(-3575 5625);
DISPLAY 1.021277 (-3575 5625);
DISPLAY INVISIBLE (-3575 5625);
FORCEADD VCC15..1
(-3400 5800);
FORCEPROP 3 LASTPIN (-3400 5750) SIG_NAME SW_P12V_PVCCIN_CPU1_FLT\g
J 0
(-3390 5760);
DISPLAY 0.659574 (-3390 5760);
PAINT MONO (-3390 5760);
DISPLAY INVISIBLE (-3390 5760);
FORCEPROP 1 LAST HDL_POWER SW_P12V_PVCCIN_CPU1_FLT
J 1
(-3350 5850);
DISPLAY 0.617021 (-3350 5850);
PAINT GREEN (-3350 5850);
FORCEPROP 2 LAST CDS_LIB logical_power
J 0
(-3400 5800);
DISPLAY INVISIBLE (-3400 5800);
FORCEPROP 1 LAST PATH I63
J 0
(-3350 5825);
DISPLAY 0.872340 (-3350 5825);
PAINT AQUA (-3350 5825);
DISPLAY INVISIBLE (-3350 5825);
FORCEADD Q_CAP..1
(-1675 4325);
FORCEPROP 1 LAST PART_NUMBER CH5103KEB01
J 0
(-1625 4150);
DISPLAY 0.617021 (-1625 4150);
PAINT BLUE (-1625 4150);
DISPLAY INVISIBLE (-1625 4150);
FORCEPROP 1 LAST MATERIAL X6S
J 0
(-1625 4250);
DISPLAY 0.617021 (-1625 4250);
PAINT SKYBLUE (-1625 4250);
FORCEPROP 1 LAST TOLERANCE 10%
J 0
(-1625 4300);
DISPLAY 0.617021 (-1625 4300);
PAINT SKYBLUE (-1625 4300);
FORCEPROP 1 LAST VALUE 1UF
J 0
(-1625 4400);
DISPLAY 0.617021 (-1625 4400);
PAINT SKYBLUE (-1625 4400);
FORCEPROP 1 LAST VOLTAGE 16V
J 0
(-1625 4350);
DISPLAY 0.617021 (-1625 4350);
PAINT SKYBLUE (-1625 4350);
FORCEPROP 1 LAST PACK_TYPE C0402
J 0
(-1625 4200);
DISPLAY 0.617021 (-1625 4200);
PAINT SKYBLUE (-1625 4200);
FORCEPROP 1 LAST LOCATION PC496_P1_7
J 0
(-1625 4450);
DISPLAY 0.617021 (-1625 4450);
PAINT AQUA (-1625 4450);
FORCEPROP 1 LASTPIN (-1675 4425) $PN 1
J 0
(-1665 4405);
DISPLAY 0.617021 (-1665 4405);
PAINT MONO (-1665 4405);
FORCEPROP 1 LASTPIN (-1675 4225) $PN 2
J 0
(-1665 4205);
DISPLAY 0.617021 (-1665 4205);
PAINT MONO (-1665 4205);
FORCEPROP 2 LAST CDS_LIB pure_quanta
J 0
(-1675 4325);
DISPLAY INVISIBLE (-1675 4325);
FORCEPROP 1 LAST PATH I64
J 0
(-1625 4475);
DISPLAY 0.978723 (-1625 4475);
PAINT WHITE (-1625 4475);
DISPLAY INVISIBLE (-1625 4475);
FORCEPROP 1 LAST LOCATION PC496_P1_7
J 0
(-1625 4500);
DISPLAY 1.021277 (-1625 4500);
PAINT AQUA (-1625 4500);
DISPLAY INVISIBLE (-1625 4500);
FORCEPROP 0 LAST $SEC 1
J 0
(-1625 4500);
DISPLAY 0.680851 (-1625 4500);
PAINT MONO (-1625 4500);
DISPLAY INVISIBLE (-1625 4500);
FORCEPROP 0 LAST CDS_SEC 1
J 0
(-1625 4500);
DISPLAY 1.021277 (-1625 4500);
DISPLAY INVISIBLE (-1625 4500);
FORCEADD Q_CAP..1
(-1250 4325);
FORCEPROP 1 LAST PART_NUMBER CH622KMEA03
J 0
(-1200 4150);
DISPLAY 0.617021 (-1200 4150);
PAINT BLUE (-1200 4150);
DISPLAY INVISIBLE (-1200 4150);
FORCEPROP 1 LAST PACK_TYPE C0805
J 0
(-1200 4200);
DISPLAY 0.617021 (-1200 4200);
PAINT SKYBLUE (-1200 4200);
FORCEPROP 1 LAST VOLTAGE 4V
J 0
(-1200 4350);
DISPLAY 0.617021 (-1200 4350);
PAINT SKYBLUE (-1200 4350);
FORCEPROP 1 LAST VALUE 22UF
J 0
(-1200 4400);
DISPLAY 0.617021 (-1200 4400);
PAINT SKYBLUE (-1200 4400);
FORCEPROP 1 LAST TOLERANCE 20%
J 0
(-1200 4300);
DISPLAY 0.617021 (-1200 4300);
PAINT SKYBLUE (-1200 4300);
FORCEPROP 1 LAST MATERIAL X6S
J 0
(-1200 4250);
DISPLAY 0.617021 (-1200 4250);
PAINT SKYBLUE (-1200 4250);
FORCEPROP 1 LAST LOCATION PC498_P1_7
J 0
(-1200 4450);
DISPLAY 0.617021 (-1200 4450);
PAINT AQUA (-1200 4450);
FORCEPROP 1 LASTPIN (-1250 4425) $PN 1
J 0
(-1240 4405);
DISPLAY 0.617021 (-1240 4405);
PAINT MONO (-1240 4405);
FORCEPROP 1 LASTPIN (-1250 4225) $PN 2
J 0
(-1240 4205);
DISPLAY 0.617021 (-1240 4205);
PAINT MONO (-1240 4205);
FORCEPROP 2 LAST CDS_LIB pure_quanta
J 0
(-1250 4325);
DISPLAY INVISIBLE (-1250 4325);
FORCEPROP 1 LAST PATH I65
J 0
(-1200 4475);
DISPLAY 0.978723 (-1200 4475);
PAINT WHITE (-1200 4475);
DISPLAY INVISIBLE (-1200 4475);
FORCEPROP 1 LAST LOCATION PC498_P1_7
J 0
(-1200 4500);
DISPLAY 1.021277 (-1200 4500);
PAINT AQUA (-1200 4500);
DISPLAY INVISIBLE (-1200 4500);
FORCEPROP 0 LAST $SEC 1
J 0
(-1200 4500);
DISPLAY 0.680851 (-1200 4500);
PAINT MONO (-1200 4500);
DISPLAY INVISIBLE (-1200 4500);
FORCEPROP 0 LAST CDS_SEC 1
J 0
(-1200 4500);
DISPLAY 1.021277 (-1200 4500);
DISPLAY INVISIBLE (-1200 4500);
FORCEADD Q_CAP..1
(-825 4325);
FORCEPROP 1 LAST PART_NUMBER CH622KMEA03
J 0
(-775 4150);
DISPLAY 0.617021 (-775 4150);
PAINT BLUE (-775 4150);
DISPLAY INVISIBLE (-775 4150);
FORCEPROP 1 LAST PACK_TYPE C0805
J 0
(-775 4200);
DISPLAY 0.617021 (-775 4200);
PAINT SKYBLUE (-775 4200);
FORCEPROP 1 LAST VOLTAGE 4V
J 0
(-775 4350);
DISPLAY 0.617021 (-775 4350);
PAINT SKYBLUE (-775 4350);
FORCEPROP 1 LAST VALUE 22UF
J 0
(-775 4400);
DISPLAY 0.617021 (-775 4400);
PAINT SKYBLUE (-775 4400);
FORCEPROP 1 LAST TOLERANCE 20%
J 0
(-775 4300);
DISPLAY 0.617021 (-775 4300);
PAINT SKYBLUE (-775 4300);
FORCEPROP 1 LAST MATERIAL X6S
J 0
(-775 4250);
DISPLAY 0.617021 (-775 4250);
PAINT SKYBLUE (-775 4250);
FORCEPROP 1 LAST LOCATION PC500_P1_7
J 0
(-775 4450);
DISPLAY 0.617021 (-775 4450);
PAINT AQUA (-775 4450);
FORCEPROP 1 LASTPIN (-825 4425) $PN 1
J 0
(-815 4405);
DISPLAY 0.617021 (-815 4405);
PAINT MONO (-815 4405);
FORCEPROP 1 LASTPIN (-825 4225) $PN 2
J 0
(-815 4205);
DISPLAY 0.617021 (-815 4205);
PAINT MONO (-815 4205);
FORCEPROP 2 LAST CDS_LIB pure_quanta
J 0
(-825 4325);
DISPLAY INVISIBLE (-825 4325);
FORCEPROP 1 LAST PATH I66
J 0
(-775 4475);
DISPLAY 0.978723 (-775 4475);
PAINT WHITE (-775 4475);
DISPLAY INVISIBLE (-775 4475);
FORCEPROP 1 LAST LOCATION PC500_P1_7
J 0
(-775 4500);
DISPLAY 1.021277 (-775 4500);
PAINT AQUA (-775 4500);
DISPLAY INVISIBLE (-775 4500);
FORCEPROP 0 LAST $SEC 1
J 0
(-775 4500);
DISPLAY 0.680851 (-775 4500);
PAINT MONO (-775 4500);
DISPLAY INVISIBLE (-775 4500);
FORCEPROP 0 LAST CDS_SEC 1
J 0
(-775 4500);
DISPLAY 1.021277 (-775 4500);
DISPLAY INVISIBLE (-775 4500);
FORCEADD VCC15..1
(-525 4725);
FORCEPROP 3 LASTPIN (-525 4675) SIG_NAME PVCCIN_CPU1\g
J 0
(-515 4685);
DISPLAY 0.659574 (-515 4685);
PAINT MONO (-515 4685);
DISPLAY INVISIBLE (-515 4685);
FORCEPROP 1 LAST HDL_POWER PVCCIN_CPU1
J 1
(-525 4775);
DISPLAY 0.617021 (-525 4775);
PAINT GREEN (-525 4775);
FORCEPROP 2 LAST CDS_LIB logical_power
J 0
(-525 4725);
DISPLAY INVISIBLE (-525 4725);
FORCEPROP 1 LAST PATH I67
J 0
(-475 4750);
DISPLAY 0.872340 (-475 4750);
PAINT AQUA (-475 4750);
DISPLAY INVISIBLE (-475 4750);
FORCEADD Q_RES..2
(-7525 5525);
FORCEPROP 1 LAST PART_NUMBER CS-2202FB01
J 0
(-7485 5400);
DISPLAY 0.617021 (-7485 5400);
PAINT BLUE (-7485 5400);
DISPLAY INVISIBLE (-7485 5400);
FORCEPROP 1 LAST WATTAGE 1/16W
J 0
(-7485 5500);
DISPLAY 0.617021 (-7485 5500);
PAINT SKYBLUE (-7485 5500);
FORCEPROP 1 LAST MATERIAL CHIP
J 0
(-7485 5450);
DISPLAY 0.617021 (-7485 5450);
PAINT SKYBLUE (-7485 5450);
FORCEPROP 1 LAST TOLERANCE 1%
J 0
(-7480 5550);
DISPLAY 0.617021 (-7480 5550);
PAINT SKYBLUE (-7480 5550);
FORCEPROP 1 LAST VALUE 2.2
J 0
(-7480 5600);
DISPLAY 0.617021 (-7480 5600);
PAINT SKYBLUE (-7480 5600);
FORCEPROP 1 LAST PACK_TYPE 0402LF
J 0
(-7485 5350);
DISPLAY 0.617021 (-7485 5350);
PAINT SKYBLUE (-7485 5350);
FORCEPROP 1 LAST LOCATION PR288
J 0
(-7480 5650);
DISPLAY 0.617021 (-7480 5650);
PAINT AQUA (-7480 5650);
FORCEPROP 1 LASTPIN (-7525 5625) $PN 1
J 0
(-7520 5587);
DISPLAY 0.617021 (-7520 5587);
PAINT MONO (-7520 5587);
FORCEPROP 1 LASTPIN (-7525 5425) $PN 2
J 0
(-7520 5435);
DISPLAY 0.617021 (-7520 5435);
PAINT MONO (-7520 5435);
FORCEPROP 2 LAST CDS_LIB pure_quanta
J 0
(-7525 5525);
DISPLAY INVISIBLE (-7525 5525);
FORCEPROP 1 LAST PATH I68
J 0
(-7475 5700);
DISPLAY 0.978723 (-7475 5700);
PAINT WHITE (-7475 5700);
DISPLAY INVISIBLE (-7475 5700);
FORCEPROP 1 LAST LOCATION PR288
J 0
(-7475 5700);
DISPLAY 1.021277 (-7475 5700);
PAINT AQUA (-7475 5700);
DISPLAY INVISIBLE (-7475 5700);
FORCEPROP 0 LAST $SEC 1
J 0
(-7475 5700);
DISPLAY 0.680851 (-7475 5700);
PAINT MONO (-7475 5700);
DISPLAY INVISIBLE (-7475 5700);
FORCEPROP 0 LAST CDS_SEC 1
J 0
(-7475 5700);
DISPLAY 1.021277 (-7475 5700);
DISPLAY INVISIBLE (-7475 5700);
FORCEADD Q_CAP..1
(-7100 5525);
FORCEPROP 1 LAST PART_NUMBER CH5222KEB01
J 0
(-7050 5400);
DISPLAY 0.617021 (-7050 5400);
PAINT BLUE (-7050 5400);
DISPLAY INVISIBLE (-7050 5400);
FORCEPROP 1 LAST MATERIAL X6S
J 0
(-7050 5450);
DISPLAY 0.617021 (-7050 5450);
PAINT SKYBLUE (-7050 5450);
FORCEPROP 1 LAST TOLERANCE 10%
J 0
(-7050 5500);
DISPLAY 0.617021 (-7050 5500);
PAINT SKYBLUE (-7050 5500);
FORCEPROP 1 LAST VALUE 2.2UF
J 0
(-7050 5600);
DISPLAY 0.617021 (-7050 5600);
PAINT SKYBLUE (-7050 5600);
FORCEPROP 1 LAST VOLTAGE 10V
J 0
(-7050 5550);
DISPLAY 0.617021 (-7050 5550);
PAINT SKYBLUE (-7050 5550);
FORCEPROP 1 LAST PACK_TYPE C0402
J 0
(-7050 5350);
DISPLAY 0.617021 (-7050 5350);
PAINT SKYBLUE (-7050 5350);
FORCEPROP 1 LAST LOCATION PC482_P1_7
J 0
(-7050 5650);
DISPLAY 0.617021 (-7050 5650);
PAINT AQUA (-7050 5650);
FORCEPROP 1 LASTPIN (-7100 5625) $PN 1
J 0
(-7090 5605);
DISPLAY 0.617021 (-7090 5605);
PAINT MONO (-7090 5605);
FORCEPROP 1 LASTPIN (-7100 5425) $PN 2
J 0
(-7090 5405);
DISPLAY 0.617021 (-7090 5405);
PAINT MONO (-7090 5405);
FORCEPROP 2 LAST CDS_LIB pure_quanta
J 0
(-7100 5525);
DISPLAY INVISIBLE (-7100 5525);
FORCEPROP 1 LAST PATH I69
J 0
(-7050 5675);
DISPLAY 0.978723 (-7050 5675);
PAINT WHITE (-7050 5675);
DISPLAY INVISIBLE (-7050 5675);
FORCEPROP 1 LAST LOCATION PC482_P1_7
J 0
(-7050 5700);
DISPLAY 1.021277 (-7050 5700);
PAINT AQUA (-7050 5700);
DISPLAY INVISIBLE (-7050 5700);
FORCEPROP 0 LAST $SEC 1
J 0
(-7050 5700);
DISPLAY 0.680851 (-7050 5700);
PAINT MONO (-7050 5700);
DISPLAY INVISIBLE (-7050 5700);
FORCEPROP 0 LAST CDS_SEC 1
J 0
(-7050 5700);
DISPLAY 1.021277 (-7050 5700);
DISPLAY INVISIBLE (-7050 5700);
FORCEADD Q_CAP..2
(-7225 1500);
FORCEPROP 1 LAST PART_NUMBER CH4104K1B00
J 1
(-7000 1525);
DISPLAY 0.617021 (-7000 1525);
PAINT BLUE (-7000 1525);
DISPLAY INVISIBLE (-7000 1525);
FORCEPROP 1 LAST MATERIAL X7R
J 0
(-6850 1525);
DISPLAY 0.617021 (-6850 1525);
PAINT SKYBLUE (-6850 1525);
FORCEPROP 1 LAST TOLERANCE 10%
J 2
(-6700 1525);
DISPLAY 0.617021 (-6700 1525);
PAINT SKYBLUE (-6700 1525);
FORCEPROP 1 LAST VALUE 0.1UF
J 2
(-7000 1500);
DISPLAY 0.617021 (-7000 1500);
PAINT SKYBLUE (-7000 1500);
FORCEPROP 1 LAST VOLTAGE 25V
J 0
(-6975 1500);
DISPLAY 0.617021 (-6975 1500);
PAINT SKYBLUE (-6975 1500);
FORCEPROP 1 LAST PACK_TYPE 0402
J 1
(-6850 1500);
DISPLAY 0.617021 (-6850 1500);
PAINT SKYBLUE (-6850 1500);
FORCEPROP 1 LAST LOCATION PC1362
J 1
(-7425 1500);
DISPLAY 0.617021 (-7425 1500);
PAINT AQUA (-7425 1500);
FORCEPROP 1 LASTPIN (-7325 1500) $PN 1
J 0
(-7335 1515);
DISPLAY 0.617021 (-7335 1515);
FORCEPROP 1 LASTPIN (-7125 1500) $PN 2
J 0
(-7140 1515);
DISPLAY 0.617021 (-7140 1515);
FORCEPROP 2 LAST CDS_LIB pure_quanta
J 0
(-7225 1500);
PAINT MONO (-7225 1500);
DISPLAY INVISIBLE (-7225 1500);
FORCEPROP 1 LAST PATH I7
J 0
(-7225 1700);
DISPLAY 0.978723 (-7225 1700);
PAINT WHITE (-7225 1700);
DISPLAY INVISIBLE (-7225 1700);
FORCEPROP 2 LAST $SEC 1
J 0
(-7225 1750);
DISPLAY 0.680851 (-7225 1750);
PAINT MONO (-7225 1750);
DISPLAY INVISIBLE (-7225 1750);
FORCEPROP 2 LAST CDS_SEC 1
J 0
(-7225 1750);
DISPLAY 1.021277 (-7225 1750);
DISPLAY INVISIBLE (-7225 1750);
FORCEADD OFFPAGE..5
(-7475 1700);
FORCEPROP 2 LAST $XR0 284 
J 0
(-7760 1700);
DISPLAY 0.638298 (-7760 1700);
PAINT MONO (-7760 1700);
FORCEPROP 1 LAST COMMENT_BODY TRUE
J 0
(-7375 1625);
DISPLAY 0.872340 (-7375 1625);
PAINT GREEN (-7375 1625);
DISPLAY INVISIBLE (-7375 1625);
FORCEPROP 1 LAST OFFPAGE TRUE
J 0
(-7150 1575);
DISPLAY 0.872340 (-7150 1575);
PAINT GREEN (-7150 1575);
DISPLAY INVISIBLE (-7150 1575);
FORCEPROP 2 LAST CDS_LIB standard
J 0
(-7475 1700);
DISPLAY INVISIBLE (-7475 1700);
FORCEPROP 2 LAST PATH I8
J 0
(-7750 1750);
DISPLAY 1.021277 (-7750 1750);
DISPLAY INVISIBLE (-7750 1750);
FORCEADD Q_CAP..1
(-7550 2200);
FORCEPROP 1 LAST PART_NUMBER CH5222KEB01
J 0
(-7500 2025);
DISPLAY 0.617021 (-7500 2025);
PAINT BLUE (-7500 2025);
DISPLAY INVISIBLE (-7500 2025);
FORCEPROP 1 LAST MATERIAL X6S
J 0
(-7500 2125);
DISPLAY 0.617021 (-7500 2125);
PAINT SKYBLUE (-7500 2125);
FORCEPROP 1 LAST TOLERANCE 10%
J 0
(-7500 2175);
DISPLAY 0.617021 (-7500 2175);
PAINT SKYBLUE (-7500 2175);
FORCEPROP 1 LAST VALUE 2.2UF
J 0
(-7500 2275);
DISPLAY 0.617021 (-7500 2275);
PAINT SKYBLUE (-7500 2275);
FORCEPROP 1 LAST VOLTAGE 10V
J 0
(-7500 2225);
DISPLAY 0.617021 (-7500 2225);
PAINT SKYBLUE (-7500 2225);
FORCEPROP 1 LAST PACK_TYPE C0402
J 0
(-7500 2075);
DISPLAY 0.617021 (-7500 2075);
PAINT SKYBLUE (-7500 2075);
FORCEPROP 1 LAST LOCATION PC479
J 0
(-7500 2325);
DISPLAY 0.617021 (-7500 2325);
PAINT AQUA (-7500 2325);
FORCEPROP 1 LASTPIN (-7550 2300) $PN 1
J 0
(-7540 2280);
DISPLAY 0.617021 (-7540 2280);
PAINT MONO (-7540 2280);
FORCEPROP 1 LASTPIN (-7550 2100) $PN 2
J 0
(-7540 2080);
DISPLAY 0.617021 (-7540 2080);
PAINT MONO (-7540 2080);
FORCEPROP 2 LAST CDS_LIB pure_quanta
J 0
(-7550 2200);
DISPLAY INVISIBLE (-7550 2200);
FORCEPROP 1 LAST PATH I9
J 0
(-7500 2350);
DISPLAY 0.978723 (-7500 2350);
PAINT WHITE (-7500 2350);
DISPLAY INVISIBLE (-7500 2350);
FORCEPROP 1 LAST LOCATION PC479
J 0
(-7500 2375);
DISPLAY 1.021277 (-7500 2375);
PAINT AQUA (-7500 2375);
DISPLAY INVISIBLE (-7500 2375);
FORCEPROP 0 LAST $SEC 1
J 0
(-7500 2375);
DISPLAY 0.680851 (-7500 2375);
PAINT MONO (-7500 2375);
DISPLAY INVISIBLE (-7500 2375);
FORCEPROP 0 LAST CDS_SEC 1
J 0
(-7500 2375);
DISPLAY 1.021277 (-7500 2375);
DISPLAY INVISIBLE (-7500 2375);
FORCEADD DNS..1
(-7950 1175);
PAINT RED (-7950 1175);
FORCEPROP 2 LAST CDS_LIB mstr_misc
J 0
(-7950 1175);
PAINT MONO (-7950 1175);
DISPLAY INVISIBLE (-7950 1175);
FORCEPROP 1 LAST COMMENT_BODY TRUE
R 1
J 0
(-7875 950);
DISPLAY 0.872340 (-7875 950);
PAINT GREEN (-7875 950);
DISPLAY INVISIBLE (-7875 950);
FORCEADD DNS..1
(-7925 4000);
PAINT RED (-7925 4000);
FORCEPROP 2 LAST CDS_LIB mstr_misc
J 0
(-7925 4000);
PAINT MONO (-7925 4000);
DISPLAY INVISIBLE (-7925 4000);
FORCEPROP 1 LAST COMMENT_BODY TRUE
R 1
J 0
(-7850 3775);
DISPLAY 0.872340 (-7850 3775);
PAINT GREEN (-7850 3775);
DISPLAY INVISIBLE (-7850 3775);
FORCEADD QUANTA_TITLE_BLOCK_C..1
(-75 175);
FORCEPROP 0 LAST CDS_CON_LAST_MODIFIED Fri Aug 25 14:04:59 2023
J 0
(-1960 190);
DISPLAY INVISIBLE (-1960 190);
FORCEPROP 1 LAST CUSTOM_TXT_CDS <CON_LAST_MODIFIED>
J 0
(-1960 190);
DISPLAY 0.978723 (-1960 190);
FORCEPROP 2 LAST CUSTOM_TXT_CDS <XR_PAGE_TITLE>
J 0
(-7965 5425);
DISPLAY 0.638298 (-7965 5425);
PAINT PINK (-7965 5425);
DISPLAY INVISIBLE (-7965 5425);
FORCEPROP 1 LAST CUSTOM_TXT_CDS <NAME_2>
J 0
(-3250 225);
FORCEPROP 1 LAST CUSTOM_TXT_CDS <NAME_1>
J 0
(-3250 350);
FORCEPROP 1 LAST CUSTOM_TXT_CDS <Q_NUMBER>
J 0
(-1478 278);
DISPLAY 1.212766 (-1478 278);
FORCEPROP 1 LAST CUSTOM_TXT_CDS <Q_PROJ>
J 0
(-2457 277);
DISPLAY 1.212766 (-2457 277);
FORCEPROP 1 LAST CUSTOM_TXT_CDS <Q_REV>
J 0
(-259 278);
DISPLAY 1.212766 (-259 278);
FORCEPROP 1 LAST CUSTOM_TXT_CDS <CON_PAGE_NUM> OF <CON_TOTAL_PAGES>
J 0
(-521 193);
DISPLAY 0.978723 (-521 193);
FORCEPROP 1 LAST Q_TITLE VCCIN CPU1 VR PHASE 7&8 (5/7)
J 0
(-9375 225);
DISPLAY 2.446809 (-9375 225);
PAINT GREEN (-9375 225);
FORCEPROP 1 LAST Q_DEPT 
J 1
(-3838 224);
DISPLAY 1.957447 (-3838 224);
PAINT GREEN (-3838 224);
FORCEPROP 2 LAST CDS_XR_PAGE_TITLE CR-288 : @S9S_MB_2U_LIB.S9S_MB_2U(SCH_1):PAGE288
J 0
(-7965 5425);
DISPLAY 0.638298 (-7965 5425);
PAINT PINK (-7965 5425);
DISPLAY INVISIBLE (-7965 5425);
FORCEPROP 1 LAST COMMENT_BODY TRUE
J 0
(-63 162);
DISPLAY 0.978723 (-63 162);
PAINT GREEN (-63 162);
DISPLAY INVISIBLE (-63 162);
FORCEPROP 2 LAST PAGE_BORDER TRUE
J 0
(-7965 5425);
DISPLAY 0.638298 (-7965 5425);
PAINT PINK (-7965 5425);
DISPLAY INVISIBLE (-7965 5425);
FORCEPROP 1 LAST CDS_LMAN_SYM_OUTLINE -9475,6775,100,-125
J 0
(-75 175);
DISPLAY 0.468085 (-75 175);
PAINT GREEN (-75 175);
DISPLAY INVISIBLE (-75 175);
FORCEPROP 2 LAST CDS_LIB pure_quanta
J 0
(-75 175);
DISPLAY INVISIBLE (-75 175);
WIRE 16 -1 (-7550 2925)(-7550 2975);
WIRE 16 -1 (-7125 2925)(-7550 2925);
WIRE 16 -1 (-7550 2800)(-7550 2925);
WIRE 16 -1 (-7525 5750)(-7525 5800);
WIRE 16 -1 (-7100 5750)(-7525 5750);
WIRE 16 -1 (-7525 5625)(-7525 5750);
WIRE 16 -1 (-3425 2925)(-3425 2850);
WIRE 16 -1 (-775 1850)(-775 1700);
WIRE 16 -1 (-3400 5750)(-3400 5675);
WIRE 16 -1 (-525 4675)(-525 4525);
WIRE 16 -1 (-7950 1100)(-7950 1025);
WIRE 16 -1 (-8050 1500)(-8050 1475);
WIRE 16 -1 (-8050 1500)(-7325 1500);
WIRE 16 -1 (-7550 2100)(-7550 2000);
WIRE 16 -1 (-7925 3925)(-7925 3850);
WIRE 16 -1 (-7125 2600)(-7125 2525);
WIRE 16 -1 (-5375 1100)(-5375 1025);
WIRE 16 -1 (-5375 1150)(-5375 1100);
WIRE 16 -1 (-5625 1100)(-5375 1100);
WIRE 16 -1 (-4775 1450)(-4775 1375);
WIRE 16 -1 (-4650 1450)(-4775 1450);
WIRE 16 -1 (-5350 3925)(-5350 3850);
WIRE 16 -1 (-5350 3975)(-5350 3925);
WIRE 16 -1 (-5600 3925)(-5350 3925);
WIRE 16 -1 (-8025 4325)(-8025 4300);
WIRE 16 -1 (-8025 4325)(-7300 4325);
WIRE 16 -1 (-7525 4925)(-7525 4825);
WIRE 16 -1 (-7100 5425)(-7100 5350);
WIRE 16 -1 (-3425 2225)(-3425 2350);
WIRE 16 -1 (-2975 4275)(-2975 4200);
WIRE 16 -1 (-3150 4275)(-2975 4275);
WIRE 16 -1 (-775 1175)(-775 1275);
WIRE 16 -1 (-525 4000)(-525 4100);
WIRE 16 -1 (-3400 5050)(-3400 5175);
WIRE 16 -1 (-1950 3950)(-3425 3950);
WIRE 16 -1 (-1950 4525)(-1950 3950);
WIRE 16 -1 (-1950 4525)(-3150 4525);
WIRE 16 -1 (-1675 4525)(-1950 4525);
WIRE 16 -1 (-1675 4425)(-1675 4525);
WIRE 16 -1 (-1675 4525)(-1250 4525);
WIRE 16 -1 (-1250 4525)(-1250 4425);
WIRE 16 -1 (-1250 4525)(-825 4525);
WIRE 16 -1 (-825 4425)(-825 4525);
WIRE 16 -1 (-525 4525)(-825 4525);
WIRE 16 -1 (-5600 5125)(-5425 5125);
WIRE 16 -1 (-5425 5125)(-5425 5175);
WIRE 16 -1 (-5600 5175)(-5425 5175);
WIRE 16 -1 (-5425 5675)(-5425 5175);
WIRE 16 -1 (-5200 5525)(-5200 5675);
WIRE 16 -1 (-5425 5675)(-5200 5675);
WIRE 16 -1 (-5200 5675)(-4800 5675);
WIRE 16 -1 (-4800 5525)(-4800 5675);
WIRE 16 -1 (-4800 5675)(-4400 5675);
WIRE 16 -1 (-4400 5675)(-4400 5525);
WIRE 16 -1 (-4400 5675)(-4000 5675);
WIRE 16 -1 (-4000 5525)(-4000 5675);
WIRE 16 -1 (-3625 5525)(-3625 5675);
WIRE 16 -1 (-4000 5675)(-3625 5675);
WIRE 16 -1 (-3400 5675)(-3625 5675);
WIRE 16 -1 (-5200 5325)(-5200 5175);
WIRE 16 -1 (-5200 5175)(-4800 5175);
WIRE 16 -1 (-4800 5325)(-4800 5175);
WIRE 16 -1 (-4400 5175)(-4800 5175);
WIRE 16 -1 (-4400 5325)(-4400 5175);
WIRE 16 -1 (-4400 5175)(-4000 5175);
WIRE 16 -1 (-4000 5325)(-4000 5175);
WIRE 16 -1 (-4000 5175)(-3625 5175);
WIRE 16 -1 (-3625 5325)(-3625 5175);
WIRE 16 -1 (-3400 5175)(-3625 5175);
WIRE 16 -1 (-1675 4225)(-1675 4100);
WIRE 16 -1 (-1675 4100)(-1250 4100);
WIRE 16 -1 (-1250 4100)(-1250 4225);
WIRE 16 -1 (-825 4100)(-1250 4100);
WIRE 16 -1 (-825 4225)(-825 4100);
WIRE 16 -1 (-525 4100)(-825 4100);
WIRE 16 -1 (-1925 1400)(-1925 1275);
WIRE 16 -1 (-1925 1275)(-1500 1275);
WIRE 16 -1 (-1500 1275)(-1500 1400);
WIRE 16 -1 (-1075 1275)(-1500 1275);
WIRE 16 -1 (-1075 1275)(-1075 1400);
WIRE 16 -1 (-775 1275)(-1075 1275);
WIRE 16 -1 (-3425 1125)(-2125 1125);
WIRE 16 -1 (-3100 1700)(-2125 1700);
WIRE 16 -1 (-2125 1125)(-2125 1700);
WIRE 16 -1 (-2125 1700)(-1925 1700);
WIRE 16 -1 (-1925 1600)(-1925 1700);
WIRE 16 -1 (-1925 1700)(-1500 1700);
WIRE 16 -1 (-1500 1700)(-1500 1600);
WIRE 16 -1 (-1500 1700)(-1075 1700);
WIRE 16 -1 (-1075 1700)(-1075 1600);
WIRE 16 -1 (-1075 1700)(-775 1700);
WIRE 16 -1 (-5625 2300)(-5450 2300);
WIRE 16 -1 (-5450 2300)(-5450 2350);
WIRE 16 -1 (-5625 2350)(-5450 2350);
WIRE 16 -1 (-5450 2850)(-5450 2350);
WIRE 16 -1 (-5450 2850)(-5225 2850);
WIRE 16 -1 (-5225 2700)(-5225 2850);
WIRE 16 -1 (-5225 2850)(-4825 2850);
WIRE 16 -1 (-4825 2700)(-4825 2850);
WIRE 16 -1 (-4825 2850)(-4425 2850);
WIRE 16 -1 (-4425 2850)(-4425 2700);
WIRE 16 -1 (-4425 2850)(-4025 2850);
WIRE 16 -1 (-4025 2700)(-4025 2850);
WIRE 16 -1 (-4025 2850)(-3650 2850);
WIRE 16 -1 (-3650 2700)(-3650 2850);
WIRE 16 -1 (-3425 2850)(-3650 2850);
WIRE 16 -1 (-5225 2500)(-5225 2350);
WIRE 16 -1 (-5225 2350)(-4825 2350);
WIRE 16 -1 (-4825 2500)(-4825 2350);
WIRE 16 -1 (-4425 2350)(-4825 2350);
WIRE 16 -1 (-4425 2500)(-4425 2350);
WIRE 16 -1 (-4425 2350)(-4025 2350);
WIRE 16 -1 (-4025 2500)(-4025 2350);
WIRE 16 -1 (-4025 2350)(-3650 2350);
WIRE 16 -1 (-3650 2500)(-3650 2350);
WIRE 16 -1 (-3425 2350)(-3650 2350);
WIRE 16 -1 (-3100 1450)(-2625 1450);
FORCEPROP 2 LAST SIG_NAME IND_P1_CPL5
J 0
(-3010 1460);
DISPLAY 0.617021 (-3010 1460);
WIRE 16 -1 (-5625 1700)(-3900 1700);
FORCEPROP 2 LAST SIG_NAME SW_PVCCIN_CPU1_SW8
J 0
(-5435 1710);
DISPLAY 0.617021 (-5435 1710);
WIRE 16 -1 (-5600 4625)(-4025 4625);
FORCEPROP 0 LAST CDS_PHYS_NET_NAME SW_PVCCIN_CPU1_BOOTR7
J 0
(-5410 4665);
PAINT MONO (-5410 4665);
DISPLAY INVISIBLE (-5410 4665);
FORCEPROP 2 LAST SIG_NAME SW_PVCCIN_CPU1_BOOTR7
J 0
(-5410 4635);
DISPLAY 0.617021 (-5410 4635);
WIRE 16 -1 (-4025 4625)(-4025 4700);
WIRE 16 -1 (-5600 4525)(-3950 4525);
FORCEPROP 2 LAST SIG_NAME SW_PVCCIN_CPU1_SW7
J 0
(-5410 4535);
DISPLAY 0.617021 (-5410 4535);
WIRE 16 -1 (-4475 4275)(-3950 4275);
FORCEPROP 2 LAST SIG_NAME IND_P1_CPL7
J 0
(-4385 4285);
DISPLAY 0.617021 (-4385 4285);
WIRE 16 -1 (-5625 1800)(-4050 1800);
FORCEPROP 0 LAST CDS_PHYS_NET_NAME SW_PVCCIN_CPU1_BOOTR8
J 0
(-5435 1840);
PAINT MONO (-5435 1840);
DISPLAY INVISIBLE (-5435 1840);
FORCEPROP 2 LAST SIG_NAME SW_PVCCIN_CPU1_BOOTR8
J 0
(-5435 1810);
DISPLAY 0.617021 (-5435 1810);
WIRE 16 -1 (-4050 1800)(-4050 1875);
WIRE 16 -1 (-4450 1450)(-3900 1450);
FORCEPROP 2 LAST SIG_NAME IND_P1_CPL8
J 0
(-4310 1460);
DISPLAY 0.617021 (-4310 1460);
WIRE 16 -1 (-4675 2150)(-4050 2150);
FORCEPROP 2 LAST SIG_NAME SW_PVCCIN_CPU1_BOOT8_R
J 0
(-4485 2160);
DISPLAY 0.617021 (-4485 2160);
WIRE 16 -1 (-4050 2150)(-4050 2075);
WIRE 16 -1 (-4650 4975)(-4025 4975);
FORCEPROP 2 LAST SIG_NAME SW_PVCCIN_CPU1_BOOT7_R
J 0
(-4460 4985);
DISPLAY 0.617021 (-4460 4985);
WIRE 16 -1 (-4025 4975)(-4025 4900);
WIRE 16 -1 (-5600 4875)(-5450 4875);
WIRE 16 -1 (-5450 4875)(-5450 4975);
FORCEPROP 2 LAST SIG_NAME SW_PVCCIN_CPU1_BOOT7
J 0
(-5560 4985);
DISPLAY 0.617021 (-5560 4985);
WIRE 16 -1 (-5450 4975)(-4850 4975);
FORCEPROP 0 LAST CDS_PHYS_NET_NAME SW_PVCCIN_CPU1_BOOT7
J 0
(-5410 5004);
PAINT MONO (-5410 5004);
DISPLAY INVISIBLE (-5410 5004);
WIRE 16 -1 (-7100 5750)(-7100 5625);
WIRE 16 -1 (-6525 5750)(-7100 5750);
WIRE 16 -1 (-6525 5175)(-6525 5750);
WIRE 16 -1 (-6450 5175)(-6525 5175);
WIRE 16 -1 (-7525 5275)(-7525 5125);
WIRE 16 -1 (-7525 5425)(-7525 5275);
WIRE 16 -1 (-7525 5275)(-7125 5275);
WIRE 16 -1 (-7125 4875)(-7125 5275);
WIRE 16 -1 (-7125 4875)(-6550 4875);
FORCEPROP 2 LAST SIG_NAME PVCCIN_CPU1_VDD7
J 0
(-7085 4885);
DISPLAY 0.617021 (-7085 4885);
WIRE 16 -1 (-6550 4875)(-6450 4875);
WIRE 16 -1 (-6550 4675)(-6550 4875);
WIRE 16 -1 (-6450 4675)(-6550 4675);
WIRE 16 -1 (-6550 4325)(-7100 4325);
WIRE 16 -1 (-7400 4425)(-6550 4425);
FORCEPROP 2 LAST SIG_NAME PVCCIN_CPU1_VREF
J 0
(-7285 4435);
DISPLAY 0.617021 (-7285 4435);
WIRE 16 -1 (-6550 4425)(-6550 4325);
FORCEPROP 0 LAST CDS_PHYS_NET_NAME PVCCIN_CPU1_VREF
J 0
(-6550 4350);
PAINT MONO (-6550 4350);
DISPLAY INVISIBLE (-6550 4350);
WIRE 16 -1 (-6550 4425)(-6450 4425);
WIRE 16 -1 (-6450 4525)(-7400 4525);
FORCEPROP 2 LAST SIG_NAME PVCCIN_CPU1_IMON7
J 0
(-7285 4535);
DISPLAY 0.617021 (-7285 4535);
WIRE 16 -1 (-5600 4275)(-5225 4275);
WIRE 16 -1 (-5225 4275)(-5225 3950);
WIRE 16 -1 (-3625 3950)(-5225 3950);
FORCEPROP 2 LAST SIG_NAME PVCCIN_CPU1_VOS7
J 0
(-5035 3960);
DISPLAY 0.617021 (-5035 3960);
WIRE 16 -1 (-7925 4225)(-7925 4125);
WIRE 16 -1 (-7925 4225)(-6450 4225);
FORCEPROP 2 LAST SIG_NAME PVCCIN_CPU1_LSET7
J 0
(-7285 4235);
DISPLAY 0.617021 (-7285 4235);
WIRE 16 -1 (-5600 3975)(-5350 3975);
WIRE 16 -1 (-5600 4025)(-5350 4025);
WIRE 16 -1 (-5350 4025)(-5350 3975);
WIRE 16 -1 (-5350 4075)(-5350 4025);
WIRE 16 -1 (-5600 4075)(-5350 4075);
WIRE 16 -1 (-5625 2050)(-5475 2050);
WIRE 16 -1 (-5475 2050)(-5475 2150);
FORCEPROP 2 LAST SIG_NAME SW_PVCCIN_CPU1_BOOT8
J 0
(-5585 2160);
DISPLAY 0.617021 (-5585 2160);
WIRE 16 -1 (-5475 2150)(-4875 2150);
FORCEPROP 0 LAST CDS_PHYS_NET_NAME SW_PVCCIN_CPU1_BOOT8
J 0
(-5435 2179);
PAINT MONO (-5435 2179);
DISPLAY INVISIBLE (-5435 2179);
WIRE 16 -1 (-5625 1450)(-5125 1450);
WIRE 16 -1 (-5125 1450)(-5125 1125);
WIRE 16 -1 (-5125 1125)(-3625 1125);
FORCEPROP 2 LAST SIG_NAME PVCCIN_CPU1_VOS8
J 0
(-5060 1135);
DISPLAY 0.617021 (-5060 1135);
WIRE 16 -1 (-5625 1150)(-5375 1150);
WIRE 16 -1 (-5625 1200)(-5375 1200);
WIRE 16 -1 (-5375 1200)(-5375 1150);
WIRE 16 -1 (-5375 1250)(-5375 1200);
WIRE 16 -1 (-5625 1250)(-5375 1250);
WIRE 16 -1 (-7125 2925)(-7125 2800);
WIRE 16 -1 (-6550 2925)(-7125 2925);
WIRE 16 -1 (-6550 2350)(-6550 2925);
WIRE 16 -1 (-6475 2350)(-6550 2350);
WIRE 16 -1 (-6450 4025)(-7400 4025);
FORCEPROP 2 LAST SIG_NAME PVCCIN_CPU1_ATSEN
J 0
(-7285 4035);
DISPLAY 0.617021 (-7285 4035);
WIRE 16 -1 (-6450 3925)(-7400 3925);
FORCEPROP 2 LAST SIG_NAME PVCCIN_CPU1_PWM7
J 0
(-7285 3935);
DISPLAY 0.617021 (-7285 3935);
WIRE 16 -1 (-6475 1850)(-6575 1850);
WIRE 16 -1 (-6575 1850)(-6575 2050);
WIRE 16 -1 (-6475 2050)(-6575 2050);
WIRE 16 -1 (-6575 2050)(-7150 2050);
FORCEPROP 2 LAST SIG_NAME PVCCIN_CPU1_VDD8
J 0
(-7110 2060);
DISPLAY 0.617021 (-7110 2060);
WIRE 16 -1 (-7150 2050)(-7150 2450);
WIRE 16 -1 (-7550 2450)(-7550 2300);
WIRE 16 -1 (-7550 2600)(-7550 2450);
WIRE 16 -1 (-7550 2450)(-7150 2450);
WIRE 16 -1 (-6575 1500)(-7125 1500);
WIRE 16 -1 (-7425 1600)(-6575 1600);
FORCEPROP 2 LAST SIG_NAME PVCCIN_CPU1_VREF
J 0
(-7310 1610);
DISPLAY 0.617021 (-7310 1610);
WIRE 16 -1 (-6575 1600)(-6575 1500);
FORCEPROP 0 LAST CDS_PHYS_NET_NAME PVCCIN_CPU1_VREF
J 0
(-6575 1525);
PAINT MONO (-6575 1525);
DISPLAY INVISIBLE (-6575 1525);
WIRE 16 -1 (-6575 1600)(-6475 1600);
WIRE 16 -1 (-6475 1700)(-7425 1700);
FORCEPROP 2 LAST SIG_NAME PVCCIN_CPU1_IMON8
J 0
(-7310 1710);
DISPLAY 0.617021 (-7310 1710);
WIRE 16 -1 (-6475 1200)(-7425 1200);
FORCEPROP 2 LAST SIG_NAME PVCCIN_CPU1_ATSEN
J 0
(-7310 1210);
DISPLAY 0.617021 (-7310 1210);
WIRE 16 -1 (-6475 1100)(-7425 1100);
FORCEPROP 2 LAST SIG_NAME PVCCIN_CPU1_PWM8
J 0
(-7310 1110);
DISPLAY 0.617021 (-7310 1110);
WIRE 16 -1 (-7950 1400)(-7950 1300);
WIRE 16 -1 (-7950 1400)(-6475 1400);
FORCEPROP 2 LAST SIG_NAME PVCCIN_CPU1_LSET8
J 0
(-7310 1410);
DISPLAY 0.617021 (-7310 1410);
DOT 1 (-6575 1600);
DOT 1 (-6575 2050);
DOT 1 (-7550 2450);
DOT 1 (-7550 2925);
DOT 1 (-7125 2925);
DOT 1 (-5375 1100);
DOT 1 (-5375 1150);
DOT 1 (-5375 1200);
DOT 1 (-5450 2350);
DOT 1 (-5225 2850);
DOT 1 (-5350 4025);
DOT 1 (-5350 3925);
DOT 1 (-5350 3975);
DOT 1 (-4825 2350);
DOT 1 (-4825 2850);
DOT 1 (-4425 2350);
DOT 1 (-4425 2850);
DOT 1 (-7525 5275);
DOT 1 (-7525 5750);
DOT 1 (-6550 4425);
DOT 1 (-6550 4875);
DOT 1 (-7100 5750);
DOT 1 (-5425 5175);
DOT 1 (-5200 5675);
DOT 1 (-4800 5175);
DOT 1 (-4400 5175);
DOT 1 (-4800 5675);
DOT 1 (-4400 5675);
DOT 1 (-2125 1700);
DOT 1 (-4025 2350);
DOT 1 (-3650 2350);
DOT 1 (-4025 2850);
DOT 1 (-3650 2850);
DOT 1 (-1925 1700);
DOT 1 (-1500 1700);
DOT 1 (-1500 1275);
DOT 1 (-1075 1275);
DOT 1 (-1075 1700);
DOT 1 (-1250 4100);
DOT 1 (-825 4100);
DOT 1 (-4000 5175);
DOT 1 (-3625 5175);
DOT 1 (-4000 5675);
DOT 1 (-3625 5675);
DOT 1 (-1950 4525);
DOT 1 (-1675 4525);
DOT 1 (-1250 4525);
DOT 1 (-825 4525);
FORCENOTE
PVCCIN_CPU1_PHASE8
(-6400 2800) 0;
DISPLAY LEFT (-6400 2800);
DISPLAY 1.021277 (-6400 2800);
PAINT WHITE (-6400 2800);
FORCENOTE
PVCCIN_CPU1_PHASE7
(-6400 5625) 0;
DISPLAY LEFT (-6400 5625);
DISPLAY 1.021277 (-6400 5625);
PAINT WHITE (-6400 5625);
FORCENOTE
6.5*6.5*10.0
(-4525 1300) 0;
DISPLAY LEFT (-4525 1300);
DISPLAY 1.021277 (-4525 1300);
FORCENOTE
PGL6312.121AHLT 
(-4525 1375) 0;
DISPLAY LEFT (-4525 1375);
DISPLAY 1.021277 (-4525 1375);
FORCENOTE
DCR=0.17M OHM
(-4525 1150) 0;
DISPLAY LEFT (-4525 1150);
DISPLAY 1.021277 (-4525 1150);
FORCENOTE
ISAT=60A@100C
(-4525 1225) 0;
DISPLAY LEFT (-4525 1225);
DISPLAY 1.021277 (-4525 1225);
FORCENOTE
DCR=2-3,0.27M OHM
(-3150 1875) 0;
DISPLAY LEFT (-3150 1875);
DISPLAY 1.021277 (-3150 1875);
FORCENOTE
DCR=1-4,0.105M OHM
(-3150 1950) 0;
DISPLAY LEFT (-3150 1950);
DISPLAY 1.021277 (-3150 1950);
FORCENOTE
ISAT=70A@100C
(-3150 2025) 0;
DISPLAY LEFT (-3150 2025);
DISPLAY 1.021277 (-3150 2025);
FORCENOTE
11.0*7.5*12.5
(-3150 2100) 0;
DISPLAY LEFT (-3150 2100);
DISPLAY 1.021277 (-3150 2100);
FORCENOTE
PGL6303.151HLT 
(-3150 2175) 0;
DISPLAY LEFT (-3150 2175);
DISPLAY 1.021277 (-3150 2175);
FORCENOTE
DCR=2-3,0.27M OHM
(-3175 4675) 0;
DISPLAY LEFT (-3175 4675);
DISPLAY 1.021277 (-3175 4675);
FORCENOTE
DCR=1-4,0.105M OHM
(-3175 4750) 0;
DISPLAY LEFT (-3175 4750);
DISPLAY 1.021277 (-3175 4750);
FORCENOTE
PGL6303.151HLT 
(-3175 4975) 0;
DISPLAY LEFT (-3175 4975);
DISPLAY 1.021277 (-3175 4975);
FORCENOTE
ISAT=70A@100C
(-3175 4825) 0;
DISPLAY LEFT (-3175 4825);
DISPLAY 1.021277 (-3175 4825);
FORCENOTE
11.0*7.5*12.5
(-3175 4900) 0;
DISPLAY LEFT (-3175 4900);
DISPLAY 1.021277 (-3175 4900);
QUIT
